G04 CAM350 V9.0 (Build 156) Date:  Fri Dec 07 20:00:18 2012 *
G04 Database: (Untitled) *
G04 Layer 20: TMASK.art *
%FSLAX35Y35*%
%MOIN*%
%SFA1.000B1.000*%

%MIA0B0*%
%IPPOS*%
%AMMACRO25*
4,1,40,0.01700,-0.01300,0.01700,0.01300,0.01694,0.01370,0.01676,0.01437,0.01646,0.01500,0.01606,0.01557,0.01557,0.01606,0.01500,0.01646,0.01437,0.01676,0.01370,0.01694,0.01300,0.01700,-0.01300,0.01700,-0.01369,0.01694,-0.01437,0.01676,-0.01500,0.01646,-0.01557,0.01606,-0.01606,0.01557,-0.01646,0.01500,-0.01676,0.01437,-0.01694,0.01370,-0.01700,0.01300,-0.01700,-0.01300,-0.01694,-0.01369,-0.01676,-0.01437,-0.01646,-0.01500,-0.01606,-0.01557,-0.01557,-0.01606,-0.01500,-0.01646,-0.01437,-0.01676,-0.01369,-0.01694,-0.01300,-0.01700,0.01300,-0.01700,0.01370,-0.01694,0.01437,-0.01676,0.01500,-0.01646,0.01557,-0.01606,0.01606,-0.01557,0.01646,-0.01500,0.01676,-0.01437,0.01694,-0.01369,0.01700,-0.01300,0.00000*
%
%AMMACRO23*
4,1,40,0.00700,0.01100,-0.00700,0.01100,-0.00769,0.01094,-0.00837,0.01076,-0.00900,0.01046,-0.00957,0.01006,-0.01006,0.00957,-0.01046,0.00900,-0.01076,0.00837,-0.01094,0.00770,-0.01100,0.00700,-0.01100,-0.00700,-0.01094,-0.00769,-0.01076,-0.00837,-0.01046,-0.00900,-0.01006,-0.00957,-0.00957,-0.01006,-0.00900,-0.01046,-0.00837,-0.01076,-0.00769,-0.01094,-0.00700,-0.01100,0.00700,-0.01100,0.00770,-0.01094,0.00837,-0.01076,0.00900,-0.01046,0.00957,-0.01006,0.01006,-0.00957,0.01046,-0.00900,0.01076,-0.00837,0.01094,-0.00769,0.01100,-0.00700,0.01100,0.00700,0.01094,0.00770,0.01076,0.00837,0.01046,0.00900,0.01006,0.00957,0.00957,0.01006,0.00900,0.01046,0.00837,0.01076,0.00770,0.01094,0.00700,0.01100,0.00000*
%
%AMMACRO26*
4,1,40,0.00700,0.01100,-0.00700,0.01100,-0.00769,0.01094,-0.00837,0.01076,-0.00900,0.01046,-0.00957,0.01006,-0.01006,0.00957,-0.01046,0.00900,-0.01076,0.00837,-0.01094,0.00770,-0.01100,0.00700,-0.01100,-0.00700,-0.01094,-0.00769,-0.01076,-0.00837,-0.01046,-0.00900,-0.01006,-0.00957,-0.00957,-0.01006,-0.00900,-0.01046,-0.00837,-0.01076,-0.00769,-0.01094,-0.00700,-0.01100,0.00700,-0.01100,0.00770,-0.01094,0.00837,-0.01076,0.00900,-0.01046,0.00957,-0.01006,0.01006,-0.00957,0.01046,-0.00900,0.01076,-0.00837,0.01094,-0.00769,0.01100,-0.00700,0.01100,0.00700,0.01094,0.00770,0.01076,0.00837,0.01046,0.00900,0.01006,0.00957,0.00957,0.01006,0.00900,0.01046,0.00837,0.01076,0.00770,0.01094,0.00700,0.01100,0.00000*
%
%AMMACRO30*
4,1,40,-0.01300,-0.01700,0.01300,-0.01700,0.01370,-0.01694,0.01437,-0.01676,0.01500,-0.01646,0.01557,-0.01606,0.01606,-0.01557,0.01646,-0.01500,0.01676,-0.01437,0.01694,-0.01369,0.01700,-0.01300,0.01700,0.01300,0.01694,0.01370,0.01676,0.01437,0.01646,0.01500,0.01606,0.01557,0.01557,0.01606,0.01500,0.01646,0.01437,0.01676,0.01370,0.01694,0.01300,0.01700,-0.01300,0.01700,-0.01369,0.01694,-0.01437,0.01676,-0.01500,0.01646,-0.01557,0.01606,-0.01606,0.01557,-0.01646,0.01500,-0.01676,0.01437,-0.01694,0.01370,-0.01700,0.01300,-0.01700,-0.01300,-0.01694,-0.01369,-0.01676,-0.01437,-0.01646,-0.01500,-0.01606,-0.01557,-0.01557,-0.01606,-0.01500,-0.01646,-0.01437,-0.01676,-0.01369,-0.01694,-0.01300,-0.01700,0.00000*
%
%AMMACRO36*
4,1,40,-0.01300,-0.01700,0.01300,-0.01700,0.01370,-0.01694,0.01437,-0.01676,0.01500,-0.01646,0.01557,-0.01606,0.01606,-0.01557,0.01646,-0.01500,0.01676,-0.01437,0.01694,-0.01369,0.01700,-0.01300,0.01700,0.01300,0.01694,0.01370,0.01676,0.01437,0.01646,0.01500,0.01606,0.01557,0.01557,0.01606,0.01500,0.01646,0.01437,0.01676,0.01370,0.01694,0.01300,0.01700,-0.01300,0.01700,-0.01369,0.01694,-0.01437,0.01676,-0.01500,0.01646,-0.01557,0.01606,-0.01606,0.01557,-0.01646,0.01500,-0.01676,0.01437,-0.01694,0.01370,-0.01700,0.01300,-0.01700,-0.01300,-0.01694,-0.01369,-0.01676,-0.01437,-0.01646,-0.01500,-0.01606,-0.01557,-0.01557,-0.01606,-0.01500,-0.01646,-0.01437,-0.01676,-0.01369,-0.01694,-0.01300,-0.01700,0.00000*
%
%AMMACRO37*
4,1,40,0.01100,-0.00700,0.01100,0.00700,0.01094,0.00770,0.01076,0.00837,0.01046,0.00900,0.01006,0.00957,0.00957,0.01006,0.00900,0.01046,0.00837,0.01076,0.00770,0.01094,0.00700,0.01100,-0.00700,0.01100,-0.00769,0.01094,-0.00837,0.01076,-0.00900,0.01046,-0.00957,0.01006,-0.01006,0.00957,-0.01046,0.00900,-0.01076,0.00837,-0.01094,0.00770,-0.01100,0.00700,-0.01100,-0.00700,-0.01094,-0.00769,-0.01076,-0.00837,-0.01046,-0.00900,-0.01006,-0.00957,-0.00957,-0.01006,-0.00900,-0.01046,-0.00837,-0.01076,-0.00769,-0.01094,-0.00700,-0.01100,0.00700,-0.01100,0.00770,-0.01094,0.00837,-0.01076,0.00900,-0.01046,0.00957,-0.01006,0.01006,-0.00957,0.01046,-0.00900,0.01076,-0.00837,0.01094,-0.00769,0.01100,-0.00700,0.00000*
%
%AMMACRO38*
4,1,40,0.01100,-0.00700,0.01100,0.00700,0.01094,0.00770,0.01076,0.00837,0.01046,0.00900,0.01006,0.00957,0.00957,0.01006,0.00900,0.01046,0.00837,0.01076,0.00770,0.01094,0.00700,0.01100,-0.00700,0.01100,-0.00769,0.01094,-0.00837,0.01076,-0.00900,0.01046,-0.00957,0.01006,-0.01006,0.00957,-0.01046,0.00900,-0.01076,0.00837,-0.01094,0.00770,-0.01100,0.00700,-0.01100,-0.00700,-0.01094,-0.00769,-0.01076,-0.00837,-0.01046,-0.00900,-0.01006,-0.00957,-0.00957,-0.01006,-0.00900,-0.01046,-0.00837,-0.01076,-0.00769,-0.01094,-0.00700,-0.01100,0.00700,-0.01100,0.00770,-0.01094,0.00837,-0.01076,0.00900,-0.01046,0.00957,-0.01006,0.01006,-0.00957,0.01046,-0.00900,0.01076,-0.00837,0.01094,-0.00769,0.01100,-0.00700,0.00000*
%
%AMMACRO39*
4,1,40,0.00800,0.01200,-0.00800,0.01200,-0.00869,0.01194,-0.00937,0.01176,-0.01000,0.01146,-0.01057,0.01106,-0.01106,0.01057,-0.01146,0.01000,-0.01176,0.00937,-0.01194,0.00870,-0.01200,0.00800,-0.01200,-0.00800,-0.01194,-0.00869,-0.01176,-0.00937,-0.01146,-0.01000,-0.01106,-0.01057,-0.01057,-0.01106,-0.01000,-0.01146,-0.00937,-0.01176,-0.00869,-0.01194,-0.00800,-0.01200,0.00800,-0.01200,0.00870,-0.01194,0.00937,-0.01176,0.01000,-0.01146,0.01057,-0.01106,0.01106,-0.01057,0.01146,-0.01000,0.01176,-0.00937,0.01194,-0.00869,0.01200,-0.00800,0.01200,0.00800,0.01194,0.00870,0.01176,0.00937,0.01146,0.01000,0.01106,0.01057,0.01057,0.01106,0.01000,0.01146,0.00937,0.01176,0.00870,0.01194,0.00800,0.01200,0.00000*
%
%AMMACRO40*
4,1,40,0.00800,0.01200,-0.00800,0.01200,-0.00869,0.01194,-0.00937,0.01176,-0.01000,0.01146,-0.01057,0.01106,-0.01106,0.01057,-0.01146,0.01000,-0.01176,0.00937,-0.01194,0.00870,-0.01200,0.00800,-0.01200,-0.00800,-0.01194,-0.00869,-0.01176,-0.00937,-0.01146,-0.01000,-0.01106,-0.01057,-0.01057,-0.01106,-0.01000,-0.01146,-0.00937,-0.01176,-0.00869,-0.01194,-0.00800,-0.01200,0.00800,-0.01200,0.00870,-0.01194,0.00937,-0.01176,0.01000,-0.01146,0.01057,-0.01106,0.01106,-0.01057,0.01146,-0.01000,0.01176,-0.00937,0.01194,-0.00869,0.01200,-0.00800,0.01200,0.00800,0.01194,0.00870,0.01176,0.00937,0.01146,0.01000,0.01106,0.01057,0.01057,0.01106,0.01000,0.01146,0.00937,0.01176,0.00870,0.01194,0.00800,0.01200,0.00000*
%
%AMMACRO45*
4,1,40,-0.01700,0.01300,-0.01700,-0.01300,-0.01694,-0.01369,-0.01676,-0.01437,-0.01646,-0.01500,-0.01606,-0.01557,-0.01557,-0.01606,-0.01500,-0.01646,-0.01437,-0.01676,-0.01369,-0.01694,-0.01300,-0.01700,0.01300,-0.01700,0.01370,-0.01694,0.01437,-0.01676,0.01500,-0.01646,0.01557,-0.01606,0.01606,-0.01557,0.01646,-0.01500,0.01676,-0.01437,0.01694,-0.01369,0.01700,-0.01300,0.01700,0.01300,0.01694,0.01370,0.01676,0.01437,0.01646,0.01500,0.01606,0.01557,0.01557,0.01606,0.01500,0.01646,0.01437,0.01676,0.01370,0.01694,0.01300,0.01700,-0.01300,0.01700,-0.01369,0.01694,-0.01437,0.01676,-0.01500,0.01646,-0.01557,0.01606,-0.01606,0.01557,-0.01646,0.01500,-0.01676,0.01437,-0.01694,0.01370,-0.01700,0.01300,0.00000*
%
%AMMACRO46*
4,1,40,-0.01700,0.01300,-0.01700,-0.01300,-0.01694,-0.01369,-0.01676,-0.01437,-0.01646,-0.01500,-0.01606,-0.01557,-0.01557,-0.01606,-0.01500,-0.01646,-0.01437,-0.01676,-0.01369,-0.01694,-0.01300,-0.01700,0.01300,-0.01700,0.01370,-0.01694,0.01437,-0.01676,0.01500,-0.01646,0.01557,-0.01606,0.01606,-0.01557,0.01646,-0.01500,0.01676,-0.01437,0.01694,-0.01369,0.01700,-0.01300,0.01700,0.01300,0.01694,0.01370,0.01676,0.01437,0.01646,0.01500,0.01606,0.01557,0.01557,0.01606,0.01500,0.01646,0.01437,0.01676,0.01370,0.01694,0.01300,0.01700,-0.01300,0.01700,-0.01369,0.01694,-0.01437,0.01676,-0.01500,0.01646,-0.01557,0.01606,-0.01606,0.01557,-0.01646,0.01500,-0.01676,0.01437,-0.01694,0.01370,-0.01700,0.01300,0.00000*
%
%AMMACRO47*
4,1,40,0.01300,0.01700,-0.01300,0.01700,-0.01369,0.01694,-0.01437,0.01676,-0.01500,0.01646,-0.01557,0.01606,-0.01606,0.01557,-0.01646,0.01500,-0.01676,0.01437,-0.01694,0.01370,-0.01700,0.01300,-0.01700,-0.01300,-0.01694,-0.01369,-0.01676,-0.01437,-0.01646,-0.01500,-0.01606,-0.01557,-0.01557,-0.01606,-0.01500,-0.01646,-0.01437,-0.01676,-0.01369,-0.01694,-0.01300,-0.01700,0.01300,-0.01700,0.01370,-0.01694,0.01437,-0.01676,0.01500,-0.01646,0.01557,-0.01606,0.01606,-0.01557,0.01646,-0.01500,0.01676,-0.01437,0.01694,-0.01369,0.01700,-0.01300,0.01700,0.01300,0.01694,0.01370,0.01676,0.01437,0.01646,0.01500,0.01606,0.01557,0.01557,0.01606,0.01500,0.01646,0.01437,0.01676,0.01370,0.01694,0.01300,0.01700,0.00000*
%
%AMMACRO65*
4,1,40,-0.01200,0.00800,-0.01200,-0.00800,-0.01194,-0.00869,-0.01176,-0.00937,-0.01146,-0.01000,-0.01106,-0.01057,-0.01057,-0.01106,-0.01000,-0.01146,-0.00937,-0.01176,-0.00869,-0.01194,-0.00800,-0.01200,0.00800,-0.01200,0.00870,-0.01194,0.00937,-0.01176,0.01000,-0.01146,0.01057,-0.01106,0.01106,-0.01057,0.01146,-0.01000,0.01176,-0.00937,0.01194,-0.00869,0.01200,-0.00800,0.01200,0.00800,0.01194,0.00870,0.01176,0.00937,0.01146,0.01000,0.01106,0.01057,0.01057,0.01106,0.01000,0.01146,0.00937,0.01176,0.00870,0.01194,0.00800,0.01200,-0.00800,0.01200,-0.00869,0.01194,-0.00937,0.01176,-0.01000,0.01146,-0.01057,0.01106,-0.01106,0.01057,-0.01146,0.01000,-0.01176,0.00937,-0.01194,0.00870,-0.01200,0.00800,0.00000*
%
%AMMACRO66*
4,1,40,-0.01200,0.00800,-0.01200,-0.00800,-0.01194,-0.00869,-0.01176,-0.00937,-0.01146,-0.01000,-0.01106,-0.01057,-0.01057,-0.01106,-0.01000,-0.01146,-0.00937,-0.01176,-0.00869,-0.01194,-0.00800,-0.01200,0.00800,-0.01200,0.00870,-0.01194,0.00937,-0.01176,0.01000,-0.01146,0.01057,-0.01106,0.01106,-0.01057,0.01146,-0.01000,0.01176,-0.00937,0.01194,-0.00869,0.01200,-0.00800,0.01200,0.00800,0.01194,0.00870,0.01176,0.00937,0.01146,0.01000,0.01106,0.01057,0.01057,0.01106,0.01000,0.01146,0.00937,0.01176,0.00870,0.01194,0.00800,0.01200,-0.00800,0.01200,-0.00869,0.01194,-0.00937,0.01176,-0.01000,0.01146,-0.01057,0.01106,-0.01106,0.01057,-0.01146,0.01000,-0.01176,0.00937,-0.01194,0.00870,-0.01200,0.00800,0.00000*
%
%AMMACRO75*
4,1,40,-0.00700,-0.02250,-0.00839,-0.02238,-0.00974,-0.02202,-0.01100,-0.02143,-0.01214,-0.02063,-0.01313,-0.01964,-0.01393,-0.01850,-0.01452,-0.01724,-0.01488,-0.01589,-0.01500,-0.01450,-0.01500,0.01450,-0.01488,0.01589,-0.01452,0.01724,-0.01393,0.01850,-0.01313,0.01964,-0.01214,0.02063,-0.01100,0.02143,-0.00974,0.02202,-0.00839,0.02238,-0.00700,0.02250,0.00700,0.02250,0.00839,0.02238,0.00974,0.02202,0.01100,0.02143,0.01214,0.02063,0.01313,0.01964,0.01393,0.01850,0.01452,0.01724,0.01488,0.01589,0.01500,0.01450,0.01500,-0.01450,0.01488,-0.01589,0.01452,-0.01724,0.01393,-0.01850,0.01313,-0.01964,0.01214,-0.02063,0.01100,-0.02143,0.00974,-0.02202,0.00839,-0.02238,0.00700,-0.02250,-0.00700,-0.02250,0.00000*
%
%AMMACRO81*
4,1,40,-0.01400,-0.00800,-0.01400,0.00800,-0.01394,0.00870,-0.01376,0.00937,-0.01346,0.01000,-0.01306,0.01057,-0.01257,0.01106,-0.01200,0.01146,-0.01137,0.01176,-0.01069,0.01194,-0.01000,0.01200,0.01000,0.01200,0.01070,0.01194,0.01137,0.01176,0.01200,0.01146,0.01257,0.01106,0.01306,0.01057,0.01346,0.01000,0.01376,0.00937,0.01394,0.00870,0.01400,0.00800,0.01400,-0.00800,0.01394,-0.00869,0.01376,-0.00937,0.01346,-0.01000,0.01306,-0.01057,0.01257,-0.01106,0.01200,-0.01146,0.01137,-0.01176,0.01070,-0.01194,0.01000,-0.01200,-0.01000,-0.01200,-0.01069,-0.01194,-0.01137,-0.01176,-0.01200,-0.01146,-0.01257,-0.01106,-0.01306,-0.01057,-0.01346,-0.01000,-0.01376,-0.00937,-0.01394,-0.00869,-0.01400,-0.00800,0.00000*
%
%AMMACRO83*
4,1,40,0.00700,0.02250,0.00839,0.02238,0.00974,0.02202,0.01100,0.02143,0.01214,0.02063,0.01313,0.01964,0.01393,0.01850,0.01452,0.01724,0.01488,0.01589,0.01500,0.01450,0.01500,-0.01450,0.01488,-0.01589,0.01452,-0.01724,0.01393,-0.01850,0.01313,-0.01964,0.01214,-0.02063,0.01100,-0.02143,0.00974,-0.02202,0.00839,-0.02238,0.00700,-0.02250,-0.00700,-0.02250,-0.00839,-0.02238,-0.00974,-0.02202,-0.01100,-0.02143,-0.01214,-0.02063,-0.01313,-0.01964,-0.01393,-0.01850,-0.01452,-0.01724,-0.01488,-0.01589,-0.01500,-0.01450,-0.01500,0.01450,-0.01488,0.01589,-0.01452,0.01724,-0.01393,0.01850,-0.01313,0.01964,-0.01214,0.02063,-0.01100,0.02143,-0.00974,0.02202,-0.00839,0.02238,-0.00700,0.02250,0.00700,0.02250,0.00000*
%
%AMMACRO85*
4,1,25,-0.26969,-0.01299,-0.26969,-0.83465,0.26969,-0.83465,0.26969,0.83465,-0.26969,0.83465,-0.26969,0.12087,-0.22638,0.12087,-0.21476,0.11985,-0.20349,0.11683,-0.19291,0.11190,-0.18336,0.10521,-0.17511,0.09696,-0.16842,0.08741,-0.16349,0.07683,-0.16047,0.06556,-0.15945,0.05394,-0.16047,0.04232,-0.16349,0.03105,-0.16842,0.02048,-0.17511,0.01092,-0.18336,0.00267,-0.19291,-0.00402,-0.20349,-0.00895,-0.21476,-0.01197,-0.22638,-0.01299,-0.26969,-0.01299,0.00000*
%
%AMMACRO53*
4,1,40,-0.00800,-0.01200,0.00800,-0.01200,0.00870,-0.01194,0.00937,-0.01176,0.01000,-0.01146,0.01057,-0.01106,0.01106,-0.01057,0.01146,-0.01000,0.01176,-0.00937,0.01194,-0.00869,0.01200,-0.00800,0.01200,0.00800,0.01194,0.00870,0.01176,0.00937,0.01146,0.01000,0.01106,0.01057,0.01057,0.01106,0.01000,0.01146,0.00937,0.01176,0.00870,0.01194,0.00800,0.01200,-0.00800,0.01200,-0.00869,0.01194,-0.00937,0.01176,-0.01000,0.01146,-0.01057,0.01106,-0.01106,0.01057,-0.01146,0.01000,-0.01176,0.00937,-0.01194,0.00870,-0.01200,0.00800,-0.01200,-0.00800,-0.01194,-0.00869,-0.01176,-0.00937,-0.01146,-0.01000,-0.01106,-0.01057,-0.01057,-0.01106,-0.01000,-0.01146,-0.00937,-0.01176,-0.00869,-0.01194,-0.00800,-0.01200,0.00000*
%
%AMMACRO33*
4,1,40,0.01200,-0.00800,0.01200,0.00800,0.01194,0.00870,0.01176,0.00937,0.01146,0.01000,0.01106,0.01057,0.01057,0.01106,0.01000,0.01146,0.00937,0.01176,0.00870,0.01194,0.00800,0.01200,-0.00800,0.01200,-0.00869,0.01194,-0.00937,0.01176,-0.01000,0.01146,-0.01057,0.01106,-0.01106,0.01057,-0.01146,0.01000,-0.01176,0.00937,-0.01194,0.00870,-0.01200,0.00800,-0.01200,-0.00800,-0.01194,-0.00869,-0.01176,-0.00937,-0.01146,-0.01000,-0.01106,-0.01057,-0.01057,-0.01106,-0.01000,-0.01146,-0.00937,-0.01176,-0.00869,-0.01194,-0.00800,-0.01200,0.00800,-0.01200,0.00870,-0.01194,0.00937,-0.01176,0.01000,-0.01146,0.01057,-0.01106,0.01106,-0.01057,0.01146,-0.01000,0.01176,-0.00937,0.01194,-0.00869,0.01200,-0.00800,0.00000*
%
%AMMACRO28*
4,1,40,-0.00700,-0.01100,0.00700,-0.01100,0.00770,-0.01094,0.00837,-0.01076,0.00900,-0.01046,0.00957,-0.01006,0.01006,-0.00957,0.01046,-0.00900,0.01076,-0.00837,0.01094,-0.00769,0.01100,-0.00700,0.01100,0.00700,0.01094,0.00770,0.01076,0.00837,0.01046,0.00900,0.01006,0.00957,0.00957,0.01006,0.00900,0.01046,0.00837,0.01076,0.00770,0.01094,0.00700,0.01100,-0.00700,0.01100,-0.00769,0.01094,-0.00837,0.01076,-0.00900,0.01046,-0.00957,0.01006,-0.01006,0.00957,-0.01046,0.00900,-0.01076,0.00837,-0.01094,0.00770,-0.01100,0.00700,-0.01100,-0.00700,-0.01094,-0.00769,-0.01076,-0.00837,-0.01046,-0.00900,-0.01006,-0.00957,-0.00957,-0.01006,-0.00900,-0.01046,-0.00837,-0.01076,-0.00769,-0.01094,-0.00700,-0.01100,0.00000*
%
%AMMACRO19*
4,1,40,-0.01100,0.00700,-0.01100,-0.00700,-0.01094,-0.00769,-0.01076,-0.00837,-0.01046,-0.00900,-0.01006,-0.00957,-0.00957,-0.01006,-0.00900,-0.01046,-0.00837,-0.01076,-0.00769,-0.01094,-0.00700,-0.01100,0.00700,-0.01100,0.00770,-0.01094,0.00837,-0.01076,0.00900,-0.01046,0.00957,-0.01006,0.01006,-0.00957,0.01046,-0.00900,0.01076,-0.00837,0.01094,-0.00769,0.01100,-0.00700,0.01100,0.00700,0.01094,0.00770,0.01076,0.00837,0.01046,0.00900,0.01006,0.00957,0.00957,0.01006,0.00900,0.01046,0.00837,0.01076,0.00770,0.01094,0.00700,0.01100,-0.00700,0.01100,-0.00769,0.01094,-0.00837,0.01076,-0.00900,0.01046,-0.00957,0.01006,-0.01006,0.00957,-0.01046,0.00900,-0.01076,0.00837,-0.01094,0.00770,-0.01100,0.00700,0.00000*
%
%AMMACRO35*
4,1,40,0.01300,0.01700,-0.01300,0.01700,-0.01369,0.01694,-0.01437,0.01676,-0.01500,0.01646,-0.01557,0.01606,-0.01606,0.01557,-0.01646,0.01500,-0.01676,0.01437,-0.01694,0.01370,-0.01700,0.01300,-0.01700,-0.01300,-0.01694,-0.01369,-0.01676,-0.01437,-0.01646,-0.01500,-0.01606,-0.01557,-0.01557,-0.01606,-0.01500,-0.01646,-0.01437,-0.01676,-0.01369,-0.01694,-0.01300,-0.01700,0.01300,-0.01700,0.01370,-0.01694,0.01437,-0.01676,0.01500,-0.01646,0.01557,-0.01606,0.01606,-0.01557,0.01646,-0.01500,0.01676,-0.01437,0.01694,-0.01369,0.01700,-0.01300,0.01700,0.01300,0.01694,0.01370,0.01676,0.01437,0.01646,0.01500,0.01606,0.01557,0.01557,0.01606,0.01500,0.01646,0.01437,0.01676,0.01370,0.01694,0.01300,0.01700,0.00000*
%
%AMMACRO24*
4,1,40,0.01700,-0.01300,0.01700,0.01300,0.01694,0.01370,0.01676,0.01437,0.01646,0.01500,0.01606,0.01557,0.01557,0.01606,0.01500,0.01646,0.01437,0.01676,0.01370,0.01694,0.01300,0.01700,-0.01300,0.01700,-0.01369,0.01694,-0.01437,0.01676,-0.01500,0.01646,-0.01557,0.01606,-0.01606,0.01557,-0.01646,0.01500,-0.01676,0.01437,-0.01694,0.01370,-0.01700,0.01300,-0.01700,-0.01300,-0.01694,-0.01369,-0.01676,-0.01437,-0.01646,-0.01500,-0.01606,-0.01557,-0.01557,-0.01606,-0.01500,-0.01646,-0.01437,-0.01676,-0.01369,-0.01694,-0.01300,-0.01700,0.01300,-0.01700,0.01370,-0.01694,0.01437,-0.01676,0.01500,-0.01646,0.01557,-0.01606,0.01606,-0.01557,0.01646,-0.01500,0.01676,-0.01437,0.01694,-0.01369,0.01700,-0.01300,0.00000*
%
%AMMACRO64*
4,1,25,0.26969,-0.01299,0.26969,-0.83465,-0.26969,-0.83465,-0.26969,0.83465,0.26969,0.83465,0.26969,0.12087,0.22638,0.12087,0.21476,0.11985,0.20349,0.11683,0.19292,0.11190,0.18336,0.10521,0.17511,0.09696,0.16842,0.08741,0.16349,0.07683,0.16047,0.06556,0.15945,0.05394,0.16047,0.04232,0.16349,0.03105,0.16842,0.02048,0.17511,0.01092,0.18336,0.00267,0.19292,-0.00402,0.20349,-0.00895,0.21476,-0.01197,0.22638,-0.01299,0.26969,-0.01299,0.00000*
%
%AMMACRO52*
4,1,40,-0.00800,-0.01200,0.00800,-0.01200,0.00870,-0.01194,0.00937,-0.01176,0.01000,-0.01146,0.01057,-0.01106,0.01106,-0.01057,0.01146,-0.01000,0.01176,-0.00937,0.01194,-0.00869,0.01200,-0.00800,0.01200,0.00800,0.01194,0.00870,0.01176,0.00937,0.01146,0.01000,0.01106,0.01057,0.01057,0.01106,0.01000,0.01146,0.00937,0.01176,0.00870,0.01194,0.00800,0.01200,-0.00800,0.01200,-0.00869,0.01194,-0.00937,0.01176,-0.01000,0.01146,-0.01057,0.01106,-0.01106,0.01057,-0.01146,0.01000,-0.01176,0.00937,-0.01194,0.00870,-0.01200,0.00800,-0.01200,-0.00800,-0.01194,-0.00869,-0.01176,-0.00937,-0.01146,-0.01000,-0.01106,-0.01057,-0.01057,-0.01106,-0.01000,-0.01146,-0.00937,-0.01176,-0.00869,-0.01194,-0.00800,-0.01200,0.00000*
%
%AMMACRO32*
4,1,40,0.01200,-0.00800,0.01200,0.00800,0.01194,0.00870,0.01176,0.00937,0.01146,0.01000,0.01106,0.01057,0.01057,0.01106,0.01000,0.01146,0.00937,0.01176,0.00870,0.01194,0.00800,0.01200,-0.00800,0.01200,-0.00869,0.01194,-0.00937,0.01176,-0.01000,0.01146,-0.01057,0.01106,-0.01106,0.01057,-0.01146,0.01000,-0.01176,0.00937,-0.01194,0.00870,-0.01200,0.00800,-0.01200,-0.00800,-0.01194,-0.00869,-0.01176,-0.00937,-0.01146,-0.01000,-0.01106,-0.01057,-0.01057,-0.01106,-0.01000,-0.01146,-0.00937,-0.01176,-0.00869,-0.01194,-0.00800,-0.01200,0.00800,-0.01200,0.00870,-0.01194,0.00937,-0.01176,0.01000,-0.01146,0.01057,-0.01106,0.01106,-0.01057,0.01146,-0.01000,0.01176,-0.00937,0.01194,-0.00869,0.01200,-0.00800,0.00000*
%
%AMMACRO21*
4,1,40,-0.00700,-0.01100,0.00700,-0.01100,0.00770,-0.01094,0.00837,-0.01076,0.00900,-0.01046,0.00957,-0.01006,0.01006,-0.00957,0.01046,-0.00900,0.01076,-0.00837,0.01094,-0.00769,0.01100,-0.00700,0.01100,0.00700,0.01094,0.00770,0.01076,0.00837,0.01046,0.00900,0.01006,0.00957,0.00957,0.01006,0.00900,0.01046,0.00837,0.01076,0.00770,0.01094,0.00700,0.01100,-0.00700,0.01100,-0.00769,0.01094,-0.00837,0.01076,-0.00900,0.01046,-0.00957,0.01006,-0.01006,0.00957,-0.01046,0.00900,-0.01076,0.00837,-0.01094,0.00770,-0.01100,0.00700,-0.01100,-0.00700,-0.01094,-0.00769,-0.01076,-0.00837,-0.01046,-0.00900,-0.01006,-0.00957,-0.00957,-0.01006,-0.00900,-0.01046,-0.00837,-0.01076,-0.00769,-0.01094,-0.00700,-0.01100,0.00000*
%
%AMMACRO20*
4,1,40,-0.01100,0.00700,-0.01100,-0.00700,-0.01094,-0.00769,-0.01076,-0.00837,-0.01046,-0.00900,-0.01006,-0.00957,-0.00957,-0.01006,-0.00900,-0.01046,-0.00837,-0.01076,-0.00769,-0.01094,-0.00700,-0.01100,0.00700,-0.01100,0.00770,-0.01094,0.00837,-0.01076,0.00900,-0.01046,0.00957,-0.01006,0.01006,-0.00957,0.01046,-0.00900,0.01076,-0.00837,0.01094,-0.00769,0.01100,-0.00700,0.01100,0.00700,0.01094,0.00770,0.01076,0.00837,0.01046,0.00900,0.01006,0.00957,0.00957,0.01006,0.00900,0.01046,0.00837,0.01076,0.00770,0.01094,0.00700,0.01100,-0.00700,0.01100,-0.00769,0.01094,-0.00837,0.01076,-0.00900,0.01046,-0.00957,0.01006,-0.01006,0.00957,-0.01046,0.00900,-0.01076,0.00837,-0.01094,0.00770,-0.01100,0.00700,0.00000*
%
%AMMACRO20_180*
4,1,40,0.01100,-0.00700,0.01100,0.00700,0.01094,0.00769,0.01076,0.00837,0.01046,0.00900,0.01006,0.00957,0.00957,0.01006,0.00900,0.01046,0.00837,0.01076,0.00769,0.01094,0.00700,0.01100,-0.00700,0.01100,-0.00770,0.01094,-0.00837,0.01076,-0.00900,0.01046,-0.00957,0.01006,-0.01006,0.00957,-0.01046,0.00900,-0.01076,0.00837,-0.01094,0.00769,-0.01100,0.00700,-0.01100,-0.00700,-0.01094,-0.00770,-0.01076,-0.00837,-0.01046,-0.00900,-0.01006,-0.00957,-0.00957,-0.01006,-0.00900,-0.01046,-0.00837,-0.01076,-0.00770,-0.01094,-0.00700,-0.01100,0.00700,-0.01100,0.00769,-0.01094,0.00837,-0.01076,0.00900,-0.01046,0.00957,-0.01006,0.01006,-0.00957,0.01046,-0.00900,0.01076,-0.00837,0.01094,-0.00770,0.01100,-0.00700,0.00000*
%
%AMMACRO21_180*
4,1,40,0.00700,0.01100,-0.00700,0.01100,-0.00770,0.01094,-0.00837,0.01076,-0.00900,0.01046,-0.00957,0.01006,-0.01006,0.00957,-0.01046,0.00900,-0.01076,0.00837,-0.01094,0.00769,-0.01100,0.00700,-0.01100,-0.00700,-0.01094,-0.00770,-0.01076,-0.00837,-0.01046,-0.00900,-0.01006,-0.00957,-0.00957,-0.01006,-0.00900,-0.01046,-0.00837,-0.01076,-0.00770,-0.01094,-0.00700,-0.01100,0.00700,-0.01100,0.00769,-0.01094,0.00837,-0.01076,0.00900,-0.01046,0.00957,-0.01006,0.01006,-0.00957,0.01046,-0.00900,0.01076,-0.00837,0.01094,-0.00770,0.01100,-0.00700,0.01100,0.00700,0.01094,0.00769,0.01076,0.00837,0.01046,0.00900,0.01006,0.00957,0.00957,0.01006,0.00900,0.01046,0.00837,0.01076,0.00769,0.01094,0.00700,0.01100,0.00000*
%
%AMMACRO30_180*
4,1,40,0.01300,0.01700,-0.01300,0.01700,-0.01370,0.01694,-0.01437,0.01676,-0.01500,0.01646,-0.01557,0.01606,-0.01606,0.01557,-0.01646,0.01500,-0.01676,0.01437,-0.01694,0.01369,-0.01700,0.01300,-0.01700,-0.01300,-0.01694,-0.01370,-0.01676,-0.01437,-0.01646,-0.01500,-0.01606,-0.01557,-0.01557,-0.01606,-0.01500,-0.01646,-0.01437,-0.01676,-0.01370,-0.01694,-0.01300,-0.01700,0.01300,-0.01700,0.01369,-0.01694,0.01437,-0.01676,0.01500,-0.01646,0.01557,-0.01606,0.01606,-0.01557,0.01646,-0.01500,0.01676,-0.01437,0.01694,-0.01370,0.01700,-0.01300,0.01700,0.01300,0.01694,0.01369,0.01676,0.01437,0.01646,0.01500,0.01606,0.01557,0.01557,0.01606,0.01500,0.01646,0.01437,0.01676,0.01369,0.01694,0.01300,0.01700,0.00000*
%
%AMMACRO40_180*
4,1,40,-0.00800,-0.01200,0.00800,-0.01200,0.00869,-0.01194,0.00937,-0.01176,0.01000,-0.01146,0.01057,-0.01106,0.01106,-0.01057,0.01146,-0.01000,0.01176,-0.00937,0.01194,-0.00870,0.01200,-0.00800,0.01200,0.00800,0.01194,0.00869,0.01176,0.00937,0.01146,0.01000,0.01106,0.01057,0.01057,0.01106,0.01000,0.01146,0.00937,0.01176,0.00869,0.01194,0.00800,0.01200,-0.00800,0.01200,-0.00870,0.01194,-0.00937,0.01176,-0.01000,0.01146,-0.01057,0.01106,-0.01106,0.01057,-0.01146,0.01000,-0.01176,0.00937,-0.01194,0.00869,-0.01200,0.00800,-0.01200,-0.00800,-0.01194,-0.00870,-0.01176,-0.00937,-0.01146,-0.01000,-0.01106,-0.01057,-0.01057,-0.01106,-0.01000,-0.01146,-0.00937,-0.01176,-0.00870,-0.01194,-0.00800,-0.01200,0.00000*
%
%AMMACRO32_180*
4,1,40,-0.01200,0.00800,-0.01200,-0.00800,-0.01194,-0.00870,-0.01176,-0.00937,-0.01146,-0.01000,-0.01106,-0.01057,-0.01057,-0.01106,-0.01000,-0.01146,-0.00937,-0.01176,-0.00870,-0.01194,-0.00800,-0.01200,0.00800,-0.01200,0.00869,-0.01194,0.00937,-0.01176,0.01000,-0.01146,0.01057,-0.01106,0.01106,-0.01057,0.01146,-0.01000,0.01176,-0.00937,0.01194,-0.00870,0.01200,-0.00800,0.01200,0.00800,0.01194,0.00869,0.01176,0.00937,0.01146,0.01000,0.01106,0.01057,0.01057,0.01106,0.01000,0.01146,0.00937,0.01176,0.00869,0.01194,0.00800,0.01200,-0.00800,0.01200,-0.00870,0.01194,-0.00937,0.01176,-0.01000,0.01146,-0.01057,0.01106,-0.01106,0.01057,-0.01146,0.01000,-0.01176,0.00937,-0.01194,0.00869,-0.01200,0.00800,0.00000*
%
%AMMACRO23_180*
4,1,40,-0.00700,-0.01100,0.00700,-0.01100,0.00769,-0.01094,0.00837,-0.01076,0.00900,-0.01046,0.00957,-0.01006,0.01006,-0.00957,0.01046,-0.00900,0.01076,-0.00837,0.01094,-0.00770,0.01100,-0.00700,0.01100,0.00700,0.01094,0.00769,0.01076,0.00837,0.01046,0.00900,0.01006,0.00957,0.00957,0.01006,0.00900,0.01046,0.00837,0.01076,0.00769,0.01094,0.00700,0.01100,-0.00700,0.01100,-0.00770,0.01094,-0.00837,0.01076,-0.00900,0.01046,-0.00957,0.01006,-0.01006,0.00957,-0.01046,0.00900,-0.01076,0.00837,-0.01094,0.00769,-0.01100,0.00700,-0.01100,-0.00700,-0.01094,-0.00770,-0.01076,-0.00837,-0.01046,-0.00900,-0.01006,-0.00957,-0.00957,-0.01006,-0.00900,-0.01046,-0.00837,-0.01076,-0.00770,-0.01094,-0.00700,-0.01100,0.00000*
%
%AMMACRO24_180*
4,1,40,-0.01700,0.01300,-0.01700,-0.01300,-0.01694,-0.01370,-0.01676,-0.01437,-0.01646,-0.01500,-0.01606,-0.01557,-0.01557,-0.01606,-0.01500,-0.01646,-0.01437,-0.01676,-0.01370,-0.01694,-0.01300,-0.01700,0.01300,-0.01700,0.01369,-0.01694,0.01437,-0.01676,0.01500,-0.01646,0.01557,-0.01606,0.01606,-0.01557,0.01646,-0.01500,0.01676,-0.01437,0.01694,-0.01370,0.01700,-0.01300,0.01700,0.01300,0.01694,0.01369,0.01676,0.01437,0.01646,0.01500,0.01606,0.01557,0.01557,0.01606,0.01500,0.01646,0.01437,0.01676,0.01369,0.01694,0.01300,0.01700,-0.01300,0.01700,-0.01370,0.01694,-0.01437,0.01676,-0.01500,0.01646,-0.01557,0.01606,-0.01606,0.01557,-0.01646,0.01500,-0.01676,0.01437,-0.01694,0.01369,-0.01700,0.01300,0.00000*
%
%AMMACRO33_180*
4,1,40,-0.01200,0.00800,-0.01200,-0.00800,-0.01194,-0.00870,-0.01176,-0.00937,-0.01146,-0.01000,-0.01106,-0.01057,-0.01057,-0.01106,-0.01000,-0.01146,-0.00937,-0.01176,-0.00870,-0.01194,-0.00800,-0.01200,0.00800,-0.01200,0.00869,-0.01194,0.00937,-0.01176,0.01000,-0.01146,0.01057,-0.01106,0.01106,-0.01057,0.01146,-0.01000,0.01176,-0.00937,0.01194,-0.00870,0.01200,-0.00800,0.01200,0.00800,0.01194,0.00869,0.01176,0.00937,0.01146,0.01000,0.01106,0.01057,0.01057,0.01106,0.01000,0.01146,0.00937,0.01176,0.00869,0.01194,0.00800,0.01200,-0.00800,0.01200,-0.00870,0.01194,-0.00937,0.01176,-0.01000,0.01146,-0.01057,0.01106,-0.01106,0.01057,-0.01146,0.01000,-0.01176,0.00937,-0.01194,0.00869,-0.01200,0.00800,0.00000*
%
%AMMACRO52_180*
4,1,40,0.00800,0.01200,-0.00800,0.01200,-0.00870,0.01194,-0.00937,0.01176,-0.01000,0.01146,-0.01057,0.01106,-0.01106,0.01057,-0.01146,0.01000,-0.01176,0.00937,-0.01194,0.00869,-0.01200,0.00800,-0.01200,-0.00800,-0.01194,-0.00870,-0.01176,-0.00937,-0.01146,-0.01000,-0.01106,-0.01057,-0.01057,-0.01106,-0.01000,-0.01146,-0.00937,-0.01176,-0.00870,-0.01194,-0.00800,-0.01200,0.00800,-0.01200,0.00869,-0.01194,0.00937,-0.01176,0.01000,-0.01146,0.01057,-0.01106,0.01106,-0.01057,0.01146,-0.01000,0.01176,-0.00937,0.01194,-0.00870,0.01200,-0.00800,0.01200,0.00800,0.01194,0.00869,0.01176,0.00937,0.01146,0.01000,0.01106,0.01057,0.01057,0.01106,0.01000,0.01146,0.00937,0.01176,0.00869,0.01194,0.00800,0.01200,0.00000*
%
%AMMACRO25_180*
4,1,40,-0.01700,0.01300,-0.01700,-0.01300,-0.01694,-0.01370,-0.01676,-0.01437,-0.01646,-0.01500,-0.01606,-0.01557,-0.01557,-0.01606,-0.01500,-0.01646,-0.01437,-0.01676,-0.01370,-0.01694,-0.01300,-0.01700,0.01300,-0.01700,0.01369,-0.01694,0.01437,-0.01676,0.01500,-0.01646,0.01557,-0.01606,0.01606,-0.01557,0.01646,-0.01500,0.01676,-0.01437,0.01694,-0.01370,0.01700,-0.01300,0.01700,0.01300,0.01694,0.01369,0.01676,0.01437,0.01646,0.01500,0.01606,0.01557,0.01557,0.01606,0.01500,0.01646,0.01437,0.01676,0.01369,0.01694,0.01300,0.01700,-0.01300,0.01700,-0.01370,0.01694,-0.01437,0.01676,-0.01500,0.01646,-0.01557,0.01606,-0.01606,0.01557,-0.01646,0.01500,-0.01676,0.01437,-0.01694,0.01369,-0.01700,0.01300,0.00000*
%
%AMMACRO35_180*
4,1,40,-0.01300,-0.01700,0.01300,-0.01700,0.01369,-0.01694,0.01437,-0.01676,0.01500,-0.01646,0.01557,-0.01606,0.01606,-0.01557,0.01646,-0.01500,0.01676,-0.01437,0.01694,-0.01370,0.01700,-0.01300,0.01700,0.01300,0.01694,0.01369,0.01676,0.01437,0.01646,0.01500,0.01606,0.01557,0.01557,0.01606,0.01500,0.01646,0.01437,0.01676,0.01369,0.01694,0.01300,0.01700,-0.01300,0.01700,-0.01370,0.01694,-0.01437,0.01676,-0.01500,0.01646,-0.01557,0.01606,-0.01606,0.01557,-0.01646,0.01500,-0.01676,0.01437,-0.01694,0.01369,-0.01700,0.01300,-0.01700,-0.01300,-0.01694,-0.01370,-0.01676,-0.01437,-0.01646,-0.01500,-0.01606,-0.01557,-0.01557,-0.01606,-0.01500,-0.01646,-0.01437,-0.01676,-0.01370,-0.01694,-0.01300,-0.01700,0.00000*
%
%AMMACRO53_180*
4,1,40,0.00800,0.01200,-0.00800,0.01200,-0.00870,0.01194,-0.00937,0.01176,-0.01000,0.01146,-0.01057,0.01106,-0.01106,0.01057,-0.01146,0.01000,-0.01176,0.00937,-0.01194,0.00869,-0.01200,0.00800,-0.01200,-0.00800,-0.01194,-0.00870,-0.01176,-0.00937,-0.01146,-0.01000,-0.01106,-0.01057,-0.01057,-0.01106,-0.01000,-0.01146,-0.00937,-0.01176,-0.00870,-0.01194,-0.00800,-0.01200,0.00800,-0.01200,0.00869,-0.01194,0.00937,-0.01176,0.01000,-0.01146,0.01057,-0.01106,0.01106,-0.01057,0.01146,-0.01000,0.01176,-0.00937,0.01194,-0.00870,0.01200,-0.00800,0.01200,0.00800,0.01194,0.00869,0.01176,0.00937,0.01146,0.01000,0.01106,0.01057,0.01057,0.01106,0.01000,0.01146,0.00937,0.01176,0.00869,0.01194,0.00800,0.01200,0.00000*
%
%AMMACRO26_180*
4,1,40,-0.00700,-0.01100,0.00700,-0.01100,0.00769,-0.01094,0.00837,-0.01076,0.00900,-0.01046,0.00957,-0.01006,0.01006,-0.00957,0.01046,-0.00900,0.01076,-0.00837,0.01094,-0.00770,0.01100,-0.00700,0.01100,0.00700,0.01094,0.00769,0.01076,0.00837,0.01046,0.00900,0.01006,0.00957,0.00957,0.01006,0.00900,0.01046,0.00837,0.01076,0.00769,0.01094,0.00700,0.01100,-0.00700,0.01100,-0.00770,0.01094,-0.00837,0.01076,-0.00900,0.01046,-0.00957,0.01006,-0.01006,0.00957,-0.01046,0.00900,-0.01076,0.00837,-0.01094,0.00769,-0.01100,0.00700,-0.01100,-0.00700,-0.01094,-0.00770,-0.01076,-0.00837,-0.01046,-0.00900,-0.01006,-0.00957,-0.00957,-0.01006,-0.00900,-0.01046,-0.00837,-0.01076,-0.00770,-0.01094,-0.00700,-0.01100,0.00000*
%
%AMMACRO45_180*
4,1,40,0.01700,-0.01300,0.01700,0.01300,0.01694,0.01369,0.01676,0.01437,0.01646,0.01500,0.01606,0.01557,0.01557,0.01606,0.01500,0.01646,0.01437,0.01676,0.01369,0.01694,0.01300,0.01700,-0.01300,0.01700,-0.01370,0.01694,-0.01437,0.01676,-0.01500,0.01646,-0.01557,0.01606,-0.01606,0.01557,-0.01646,0.01500,-0.01676,0.01437,-0.01694,0.01369,-0.01700,0.01300,-0.01700,-0.01300,-0.01694,-0.01370,-0.01676,-0.01437,-0.01646,-0.01500,-0.01606,-0.01557,-0.01557,-0.01606,-0.01500,-0.01646,-0.01437,-0.01676,-0.01370,-0.01694,-0.01300,-0.01700,0.01300,-0.01700,0.01369,-0.01694,0.01437,-0.01676,0.01500,-0.01646,0.01557,-0.01606,0.01606,-0.01557,0.01646,-0.01500,0.01676,-0.01437,0.01694,-0.01370,0.01700,-0.01300,0.00000*
%
%AMMACRO36_180*
4,1,40,0.01300,0.01700,-0.01300,0.01700,-0.01370,0.01694,-0.01437,0.01676,-0.01500,0.01646,-0.01557,0.01606,-0.01606,0.01557,-0.01646,0.01500,-0.01676,0.01437,-0.01694,0.01369,-0.01700,0.01300,-0.01700,-0.01300,-0.01694,-0.01370,-0.01676,-0.01437,-0.01646,-0.01500,-0.01606,-0.01557,-0.01557,-0.01606,-0.01500,-0.01646,-0.01437,-0.01676,-0.01370,-0.01694,-0.01300,-0.01700,0.01300,-0.01700,0.01369,-0.01694,0.01437,-0.01676,0.01500,-0.01646,0.01557,-0.01606,0.01606,-0.01557,0.01646,-0.01500,0.01676,-0.01437,0.01694,-0.01370,0.01700,-0.01300,0.01700,0.01300,0.01694,0.01369,0.01676,0.01437,0.01646,0.01500,0.01606,0.01557,0.01557,0.01606,0.01500,0.01646,0.01437,0.01676,0.01369,0.01694,0.01300,0.01700,0.00000*
%
%AMMACRO81_180*
4,1,40,0.01400,0.00800,0.01400,-0.00800,0.01394,-0.00870,0.01376,-0.00937,0.01346,-0.01000,0.01306,-0.01057,0.01257,-0.01106,0.01200,-0.01146,0.01137,-0.01176,0.01069,-0.01194,0.01000,-0.01200,-0.01000,-0.01200,-0.01070,-0.01194,-0.01137,-0.01176,-0.01200,-0.01146,-0.01257,-0.01106,-0.01306,-0.01057,-0.01346,-0.01000,-0.01376,-0.00937,-0.01394,-0.00870,-0.01400,-0.00800,-0.01400,0.00800,-0.01394,0.00869,-0.01376,0.00937,-0.01346,0.01000,-0.01306,0.01057,-0.01257,0.01106,-0.01200,0.01146,-0.01137,0.01176,-0.01070,0.01194,-0.01000,0.01200,0.01000,0.01200,0.01069,0.01194,0.01137,0.01176,0.01200,0.01146,0.01257,0.01106,0.01306,0.01057,0.01346,0.01000,0.01376,0.00937,0.01394,0.00869,0.01400,0.00800,0.00000*
%
%AMMACRO64_180*
4,1,25,-0.26969,0.01299,-0.26969,0.83465,0.26969,0.83465,0.26969,-0.83465,-0.26969,-0.83465,-0.26969,-0.12087,-0.22638,-0.12087,-0.21476,-0.11985,-0.20349,-0.11683,-0.19292,-0.11190,-0.18336,-0.10521,-0.17511,-0.09696,-0.16842,-0.08741,-0.16349,-0.07683,-0.16047,-0.06556,-0.15945,-0.05394,-0.16047,-0.04232,-0.16349,-0.03105,-0.16842,-0.02048,-0.17511,-0.01092,-0.18336,-0.00267,-0.19292,0.00402,-0.20349,0.00895,-0.21476,0.01197,-0.22638,0.01299,-0.26969,0.01299,0.00000*
%
%AMMACRO19_180*
4,1,40,0.01100,-0.00700,0.01100,0.00700,0.01094,0.00769,0.01076,0.00837,0.01046,0.00900,0.01006,0.00957,0.00957,0.01006,0.00900,0.01046,0.00837,0.01076,0.00769,0.01094,0.00700,0.01100,-0.00700,0.01100,-0.00770,0.01094,-0.00837,0.01076,-0.00900,0.01046,-0.00957,0.01006,-0.01006,0.00957,-0.01046,0.00900,-0.01076,0.00837,-0.01094,0.00769,-0.01100,0.00700,-0.01100,-0.00700,-0.01094,-0.00770,-0.01076,-0.00837,-0.01046,-0.00900,-0.01006,-0.00957,-0.00957,-0.01006,-0.00900,-0.01046,-0.00837,-0.01076,-0.00770,-0.01094,-0.00700,-0.01100,0.00700,-0.01100,0.00769,-0.01094,0.00837,-0.01076,0.00900,-0.01046,0.00957,-0.01006,0.01006,-0.00957,0.01046,-0.00900,0.01076,-0.00837,0.01094,-0.00770,0.01100,-0.00700,0.00000*
%
%AMMACRO28_180*
4,1,40,0.00700,0.01100,-0.00700,0.01100,-0.00770,0.01094,-0.00837,0.01076,-0.00900,0.01046,-0.00957,0.01006,-0.01006,0.00957,-0.01046,0.00900,-0.01076,0.00837,-0.01094,0.00769,-0.01100,0.00700,-0.01100,-0.00700,-0.01094,-0.00770,-0.01076,-0.00837,-0.01046,-0.00900,-0.01006,-0.00957,-0.00957,-0.01006,-0.00900,-0.01046,-0.00837,-0.01076,-0.00770,-0.01094,-0.00700,-0.01100,0.00700,-0.01100,0.00769,-0.01094,0.00837,-0.01076,0.00900,-0.01046,0.00957,-0.01006,0.01006,-0.00957,0.01046,-0.00900,0.01076,-0.00837,0.01094,-0.00770,0.01100,-0.00700,0.01100,0.00700,0.01094,0.00769,0.01076,0.00837,0.01046,0.00900,0.01006,0.00957,0.00957,0.01006,0.00900,0.01046,0.00837,0.01076,0.00769,0.01094,0.00700,0.01100,0.00000*
%
%AMMACRO46_180*
4,1,40,0.01700,-0.01300,0.01700,0.01300,0.01694,0.01369,0.01676,0.01437,0.01646,0.01500,0.01606,0.01557,0.01557,0.01606,0.01500,0.01646,0.01437,0.01676,0.01369,0.01694,0.01300,0.01700,-0.01300,0.01700,-0.01370,0.01694,-0.01437,0.01676,-0.01500,0.01646,-0.01557,0.01606,-0.01606,0.01557,-0.01646,0.01500,-0.01676,0.01437,-0.01694,0.01369,-0.01700,0.01300,-0.01700,-0.01300,-0.01694,-0.01370,-0.01676,-0.01437,-0.01646,-0.01500,-0.01606,-0.01557,-0.01557,-0.01606,-0.01500,-0.01646,-0.01437,-0.01676,-0.01370,-0.01694,-0.01300,-0.01700,0.01300,-0.01700,0.01369,-0.01694,0.01437,-0.01676,0.01500,-0.01646,0.01557,-0.01606,0.01606,-0.01557,0.01646,-0.01500,0.01676,-0.01437,0.01694,-0.01370,0.01700,-0.01300,0.00000*
%
%AMMACRO37_180*
4,1,40,-0.01100,0.00700,-0.01100,-0.00700,-0.01094,-0.00770,-0.01076,-0.00837,-0.01046,-0.00900,-0.01006,-0.00957,-0.00957,-0.01006,-0.00900,-0.01046,-0.00837,-0.01076,-0.00770,-0.01094,-0.00700,-0.01100,0.00700,-0.01100,0.00769,-0.01094,0.00837,-0.01076,0.00900,-0.01046,0.00957,-0.01006,0.01006,-0.00957,0.01046,-0.00900,0.01076,-0.00837,0.01094,-0.00770,0.01100,-0.00700,0.01100,0.00700,0.01094,0.00769,0.01076,0.00837,0.01046,0.00900,0.01006,0.00957,0.00957,0.01006,0.00900,0.01046,0.00837,0.01076,0.00769,0.01094,0.00700,0.01100,-0.00700,0.01100,-0.00770,0.01094,-0.00837,0.01076,-0.00900,0.01046,-0.00957,0.01006,-0.01006,0.00957,-0.01046,0.00900,-0.01076,0.00837,-0.01094,0.00769,-0.01100,0.00700,0.00000*
%
%AMMACRO83_180*
4,1,40,-0.00700,-0.02250,-0.00839,-0.02238,-0.00974,-0.02202,-0.01100,-0.02143,-0.01214,-0.02063,-0.01313,-0.01964,-0.01393,-0.01850,-0.01452,-0.01724,-0.01488,-0.01589,-0.01500,-0.01450,-0.01500,0.01450,-0.01488,0.01589,-0.01452,0.01724,-0.01393,0.01850,-0.01313,0.01964,-0.01214,0.02063,-0.01100,0.02143,-0.00974,0.02202,-0.00839,0.02238,-0.00700,0.02250,0.00700,0.02250,0.00839,0.02238,0.00974,0.02202,0.01100,0.02143,0.01214,0.02063,0.01313,0.01964,0.01393,0.01850,0.01452,0.01724,0.01488,0.01589,0.01500,0.01450,0.01500,-0.01450,0.01488,-0.01589,0.01452,-0.01724,0.01393,-0.01850,0.01313,-0.01964,0.01214,-0.02063,0.01100,-0.02143,0.00974,-0.02202,0.00839,-0.02238,0.00700,-0.02250,-0.00700,-0.02250,0.00000*
%
%AMMACRO65_180*
4,1,40,0.01200,-0.00800,0.01200,0.00800,0.01194,0.00869,0.01176,0.00937,0.01146,0.01000,0.01106,0.01057,0.01057,0.01106,0.01000,0.01146,0.00937,0.01176,0.00869,0.01194,0.00800,0.01200,-0.00800,0.01200,-0.00870,0.01194,-0.00937,0.01176,-0.01000,0.01146,-0.01057,0.01106,-0.01106,0.01057,-0.01146,0.01000,-0.01176,0.00937,-0.01194,0.00869,-0.01200,0.00800,-0.01200,-0.00800,-0.01194,-0.00870,-0.01176,-0.00937,-0.01146,-0.01000,-0.01106,-0.01057,-0.01057,-0.01106,-0.01000,-0.01146,-0.00937,-0.01176,-0.00870,-0.01194,-0.00800,-0.01200,0.00800,-0.01200,0.00869,-0.01194,0.00937,-0.01176,0.01000,-0.01146,0.01057,-0.01106,0.01106,-0.01057,0.01146,-0.01000,0.01176,-0.00937,0.01194,-0.00870,0.01200,-0.00800,0.00000*
%
%AMMACRO38_180*
4,1,40,-0.01100,0.00700,-0.01100,-0.00700,-0.01094,-0.00770,-0.01076,-0.00837,-0.01046,-0.00900,-0.01006,-0.00957,-0.00957,-0.01006,-0.00900,-0.01046,-0.00837,-0.01076,-0.00770,-0.01094,-0.00700,-0.01100,0.00700,-0.01100,0.00769,-0.01094,0.00837,-0.01076,0.00900,-0.01046,0.00957,-0.01006,0.01006,-0.00957,0.01046,-0.00900,0.01076,-0.00837,0.01094,-0.00770,0.01100,-0.00700,0.01100,0.00700,0.01094,0.00769,0.01076,0.00837,0.01046,0.00900,0.01006,0.00957,0.00957,0.01006,0.00900,0.01046,0.00837,0.01076,0.00769,0.01094,0.00700,0.01100,-0.00700,0.01100,-0.00770,0.01094,-0.00837,0.01076,-0.00900,0.01046,-0.00957,0.01006,-0.01006,0.00957,-0.01046,0.00900,-0.01076,0.00837,-0.01094,0.00769,-0.01100,0.00700,0.00000*
%
%AMMACRO47_180*
4,1,40,-0.01300,-0.01700,0.01300,-0.01700,0.01369,-0.01694,0.01437,-0.01676,0.01500,-0.01646,0.01557,-0.01606,0.01606,-0.01557,0.01646,-0.01500,0.01676,-0.01437,0.01694,-0.01370,0.01700,-0.01300,0.01700,0.01300,0.01694,0.01369,0.01676,0.01437,0.01646,0.01500,0.01606,0.01557,0.01557,0.01606,0.01500,0.01646,0.01437,0.01676,0.01369,0.01694,0.01300,0.01700,-0.01300,0.01700,-0.01370,0.01694,-0.01437,0.01676,-0.01500,0.01646,-0.01557,0.01606,-0.01606,0.01557,-0.01646,0.01500,-0.01676,0.01437,-0.01694,0.01369,-0.01700,0.01300,-0.01700,-0.01300,-0.01694,-0.01370,-0.01676,-0.01437,-0.01646,-0.01500,-0.01606,-0.01557,-0.01557,-0.01606,-0.01500,-0.01646,-0.01437,-0.01676,-0.01370,-0.01694,-0.01300,-0.01700,0.00000*
%
%AMMACRO39_180*
4,1,40,-0.00800,-0.01200,0.00800,-0.01200,0.00869,-0.01194,0.00937,-0.01176,0.01000,-0.01146,0.01057,-0.01106,0.01106,-0.01057,0.01146,-0.01000,0.01176,-0.00937,0.01194,-0.00870,0.01200,-0.00800,0.01200,0.00800,0.01194,0.00869,0.01176,0.00937,0.01146,0.01000,0.01106,0.01057,0.01057,0.01106,0.01000,0.01146,0.00937,0.01176,0.00869,0.01194,0.00800,0.01200,-0.00800,0.01200,-0.00870,0.01194,-0.00937,0.01176,-0.01000,0.01146,-0.01057,0.01106,-0.01106,0.01057,-0.01146,0.01000,-0.01176,0.00937,-0.01194,0.00869,-0.01200,0.00800,-0.01200,-0.00800,-0.01194,-0.00870,-0.01176,-0.00937,-0.01146,-0.01000,-0.01106,-0.01057,-0.01057,-0.01106,-0.01000,-0.01146,-0.00937,-0.01176,-0.00870,-0.01194,-0.00800,-0.01200,0.00000*
%
%AMMACRO66_180*
4,1,40,0.01200,-0.00800,0.01200,0.00800,0.01194,0.00869,0.01176,0.00937,0.01146,0.01000,0.01106,0.01057,0.01057,0.01106,0.01000,0.01146,0.00937,0.01176,0.00869,0.01194,0.00800,0.01200,-0.00800,0.01200,-0.00870,0.01194,-0.00937,0.01176,-0.01000,0.01146,-0.01057,0.01106,-0.01106,0.01057,-0.01146,0.01000,-0.01176,0.00937,-0.01194,0.00869,-0.01200,0.00800,-0.01200,-0.00800,-0.01194,-0.00870,-0.01176,-0.00937,-0.01146,-0.01000,-0.01106,-0.01057,-0.01057,-0.01106,-0.01000,-0.01146,-0.00937,-0.01176,-0.00870,-0.01194,-0.00800,-0.01200,0.00800,-0.01200,0.00869,-0.01194,0.00937,-0.01176,0.01000,-0.01146,0.01057,-0.01106,0.01106,-0.01057,0.01146,-0.01000,0.01176,-0.00937,0.01194,-0.00870,0.01200,-0.00800,0.00000*
%
%AMMACRO75_180*
4,1,40,0.00700,0.02250,0.00839,0.02238,0.00974,0.02202,0.01100,0.02143,0.01214,0.02063,0.01313,0.01964,0.01393,0.01850,0.01452,0.01724,0.01488,0.01589,0.01500,0.01450,0.01500,-0.01450,0.01488,-0.01589,0.01452,-0.01724,0.01393,-0.01850,0.01313,-0.01964,0.01214,-0.02063,0.01100,-0.02143,0.00974,-0.02202,0.00839,-0.02238,0.00700,-0.02250,-0.00700,-0.02250,-0.00839,-0.02238,-0.00974,-0.02202,-0.01100,-0.02143,-0.01214,-0.02063,-0.01313,-0.01964,-0.01393,-0.01850,-0.01452,-0.01724,-0.01488,-0.01589,-0.01500,-0.01450,-0.01500,0.01450,-0.01488,0.01589,-0.01452,0.01724,-0.01393,0.01850,-0.01313,0.01964,-0.01214,0.02063,-0.01100,0.02143,-0.00974,0.02202,-0.00839,0.02238,-0.00700,0.02250,0.00700,0.02250,0.00000*
%
%AMMACRO85_180*
4,1,25,0.26969,0.01299,0.26969,0.83465,-0.26969,0.83465,-0.26969,-0.83465,0.26969,-0.83465,0.26969,-0.12087,0.22638,-0.12087,0.21476,-0.11985,0.20349,-0.11683,0.19291,-0.11190,0.18336,-0.10521,0.17511,-0.09696,0.16842,-0.08741,0.16349,-0.07683,0.16047,-0.06556,0.15945,-0.05394,0.16047,-0.04232,0.16349,-0.03105,0.16842,-0.02048,0.17511,-0.01092,0.18336,-0.00267,0.19291,0.00402,0.20349,0.00895,0.21476,0.01197,0.22638,0.01299,0.26969,0.01299,0.00000*
%
%ADD10C,0.14000*%
%ADD11R,0.16000X0.16000*%
%ADD12C,0.14200*%
%ADD13C,0.05600*%
%ADD14C,0.31500*%
%ADD15C,0.05000*%
%ADD16C,0.02800*%
%ADD17C,0.11500*%
%ADD18C,0.12600*%
%ADD19C,0.09900*%
%ADD71C,0.03200*%
%ADD20C,0.05700*%
%ADD21C,0.37500*%
%ADD23C,0.02000*%
%ADD24C,0.00600*%
%ADD27MACRO25*%
%ADD28MACRO23*%
%ADD29R,0.08000X0.12700*%
%ADD72MACRO26*%
%ADD73R,0.01400X0.06000*%
%ADD30MACRO30*%
%ADD31R,0.04500X0.03000*%
%ADD32R,0.03000X0.04500*%
%ADD33R,0.08000X0.07100*%
%ADD34R,0.08700X0.20800*%
%ADD35R,0.05000X0.06500*%
%ADD36MACRO36*%
%ADD37MACRO37*%
%ADD38MACRO38*%
%ADD39MACRO39*%
%ADD40MACRO40*%
%ADD41C,0.11500*%
%ADD42R,0.06500X0.02500*%
%ADD43C,0.09900*%
%ADD44C,0.05700*%
%ADD45MACRO45*%
%ADD46MACRO46*%
%ADD47MACRO47*%
%ADD48R,0.08500X0.12800*%
%ADD49R,0.03000X0.06400*%
%ADD50R,0.13500X0.10100*%
%ADD51C,0.03200*%
%ADD52R,0.05500X0.03500*%
%ADD53R,0.05500X0.04500*%
%ADD54R,0.20800X0.08700*%
%ADD55R,0.01600X0.04800*%
%ADD56R,0.04800X0.01600*%
%ADD57R,0.06500X0.05000*%
%ADD58R,0.09000X0.09500*%
%ADD59R,0.04000X0.02300*%
%ADD60R,0.03500X0.05500*%
%ADD61R,0.04500X0.05500*%
%ADD62R,0.09500X0.09000*%
%ADD63R,0.09000X0.04500*%
%ADD64R,0.05900X0.08900*%
%ADD65MACRO65*%
%ADD66MACRO66*%
%ADD67C,0.37500*%
%ADD68R,0.01200X0.06000*%
%ADD69R,0.06000X0.01200*%
%ADD74R,0.04000X0.01600*%
%ADD75MACRO75*%
%ADD76R,0.01600X0.04500*%
%ADD77R,0.04500X0.01600*%
%ADD78R,0.12200X0.12200*%
%ADD79R,0.12000X0.12000*%
%ADD80R,0.07100X0.06300*%
%ADD81MACRO81*%
%ADD82R,0.03000X0.04600*%
%ADD83MACRO83*%
%ADD84R,0.02200X0.04000*%
%ADD85MACRO85*%
%ADD86MACRO53*%
%ADD87MACRO33*%
%ADD88MACRO28*%
%ADD89MACRO19*%
%ADD90MACRO35*%
%ADD91MACRO24*%
%ADD92MACRO64*%
%ADD93MACRO52*%
%ADD94MACRO32*%
%ADD95MACRO21*%
%ADD96MACRO20*%
%ADD196R,0.12000X0.12000*%
%ADD198MACRO20_180*%
%ADD199MACRO21_180*%
%ADD200MACRO30_180*%
%ADD201R,0.09000X0.09500*%
%ADD202R,0.05500X0.03500*%
%ADD203MACRO40_180*%
%ADD204MACRO32_180*%
%ADD205R,0.13500X0.10100*%
%ADD206MACRO23_180*%
%ADD207MACRO24_180*%
%ADD208MACRO33_180*%
%ADD209R,0.03500X0.05500*%
%ADD210MACRO52_180*%
%ADD211R,0.05500X0.04500*%
%ADD212R,0.04500X0.05500*%
%ADD213R,0.03000X0.04500*%
%ADD214R,0.08700X0.20800*%
%ADD215MACRO25_180*%
%ADD216MACRO35_180*%
%ADD217MACRO53_180*%
%ADD218R,0.09500X0.09000*%
%ADD219R,0.06500X0.02500*%
%ADD220R,0.07100X0.06300*%
%ADD221R,0.05000X0.06500*%
%ADD222MACRO26_180*%
%ADD223R,0.09000X0.04500*%
%ADD224R,0.08000X0.07100*%
%ADD225R,0.04500X0.03000*%
%ADD226MACRO45_180*%
%ADD227MACRO36_180*%
%ADD228MACRO81_180*%
%ADD229R,0.20800X0.08700*%
%ADD230MACRO64_180*%
%ADD231MACRO19_180*%
%ADD232MACRO28_180*%
%ADD233R,0.01600X0.04800*%
%ADD234R,0.03000X0.04600*%
%ADD235R,0.01400X0.06000*%
%ADD236MACRO46_180*%
%ADD237MACRO37_180*%
%ADD238MACRO83_180*%
%ADD239R,0.04800X0.01600*%
%ADD240R,0.04000X0.01600*%
%ADD241MACRO65_180*%
%ADD242MACRO38_180*%
%ADD243R,0.08000X0.12700*%
%ADD244MACRO47_180*%
%ADD245R,0.06500X0.05000*%
%ADD246R,0.02200X0.04000*%
%ADD247MACRO39_180*%
%ADD248MACRO66_180*%
%ADD249MACRO75_180*%
%ADD250R,0.08500X0.12800*%
%ADD251R,0.05900X0.08900*%
%ADD252R,0.01600X0.04500*%
%ADD253R,0.03000X0.06400*%
%ADD254MACRO85_180*%
%ADD255R,0.04500X0.01600*%
%ADD256R,0.01200X0.06000*%
%ADD257R,0.04000X0.02300*%
%ADD258R,0.12200X0.12200*%
%ADD259R,0.06000X0.01200*%
%LNTMASK.art*%
%LPD*%
G36*
X323304Y1290689D02*
G01Y1284689D01*
X319104*
Y1290689*
X323304*
G37*
G36*
Y1282489D02*
G01Y1276489D01*
X319104*
Y1282489*
X323304*
G37*
G36*
X316904Y1290689D02*
G01Y1284689D01*
X312704*
Y1290689*
X316904*
G37*
G36*
Y1282489D02*
G01Y1276489D01*
X312704*
Y1282489*
X316904*
G37*
G36*
X-105830Y1290689D02*
G01Y1284689D01*
X-110030*
Y1290689*
X-105830*
G37*
G36*
Y1282489D02*
G01Y1276489D01*
X-110030*
Y1282489*
X-105830*
G37*
G36*
X-112230Y1290689D02*
G01Y1284689D01*
X-116430*
Y1290689*
X-112230*
G37*
G36*
Y1282489D02*
G01Y1276489D01*
X-116430*
Y1282489*
X-112230*
G37*
G36*
X527090Y677815D02*
G01Y683815D01*
X531290*
Y677815*
X527090*
G37*
G36*
Y686015D02*
G01Y692015D01*
X531290*
Y686015*
X527090*
G37*
G36*
X533490Y677815D02*
G01Y683815D01*
X537690*
Y677815*
X533490*
G37*
G36*
Y686015D02*
G01Y692015D01*
X537690*
Y686015*
X533490*
G37*
G36*
X97956Y677815D02*
G01Y683815D01*
X102156*
Y677815*
X97956*
G37*
G36*
Y686015D02*
G01Y692015D01*
X102156*
Y686015*
X97956*
G37*
G36*
X104356Y677815D02*
G01Y683815D01*
X108556*
Y677815*
X104356*
G37*
G36*
Y686015D02*
G01Y692015D01*
X108556*
Y686015*
X104356*
G37*
G36*
X283960Y377139D02*
G01Y368189D01*
X275410*
Y377139*
X283960*
G37*
G36*
Y388689D02*
G01Y379739D01*
X275410*
Y388689*
X283960*
G37*
G36*
X261110Y377139D02*
G01Y368189D01*
X252560*
Y377139*
X261110*
G37*
G36*
X249960D02*
G01Y368189D01*
X241410*
Y377139*
X249960*
G37*
G36*
X261110Y388689D02*
G01Y379739D01*
X252560*
Y388689*
X261110*
G37*
G36*
X249960D02*
G01Y379739D01*
X241410*
Y388689*
X249960*
G37*
G36*
X254610Y1513139D02*
G01Y1504189D01*
X246060*
Y1513139*
X254610*
G37*
G36*
X243460D02*
G01Y1504189D01*
X234910*
Y1513139*
X243460*
G37*
G36*
X282610D02*
G01Y1504189D01*
X274060*
Y1513139*
X282610*
G37*
G36*
X271460D02*
G01Y1504189D01*
X262910*
Y1513139*
X271460*
G37*
G36*
X254610Y1524689D02*
G01Y1515739D01*
X246060*
Y1524689*
X254610*
G37*
G36*
X243460D02*
G01Y1515739D01*
X234910*
Y1524689*
X243460*
G37*
G36*
X282610D02*
G01Y1515739D01*
X274060*
Y1524689*
X282610*
G37*
G36*
X271460D02*
G01Y1515739D01*
X262910*
Y1524689*
X271460*
G37*
G36*
X330110Y377139D02*
G01Y368189D01*
X321560*
Y377139*
X330110*
G37*
G36*
X318960D02*
G01Y368189D01*
X310410*
Y377139*
X318960*
G37*
G36*
X330110Y388689D02*
G01Y379739D01*
X321560*
Y388689*
X330110*
G37*
G36*
X318960D02*
G01Y379739D01*
X310410*
Y388689*
X318960*
G37*
G36*
X295110Y377139D02*
G01Y368189D01*
X286560*
Y377139*
X295110*
G37*
G36*
Y388689D02*
G01Y379739D01*
X286560*
Y388689*
X295110*
G37*
G36*
X327110Y1513139D02*
G01Y1504189D01*
X318560*
Y1513139*
X327110*
G37*
G36*
X315960D02*
G01Y1504189D01*
X307410*
Y1513139*
X315960*
G37*
G36*
X327110Y1524689D02*
G01Y1515739D01*
X318560*
Y1524689*
X327110*
G37*
G36*
X315960D02*
G01Y1515739D01*
X307410*
Y1524689*
X315960*
G37*
G36*
X363210Y377039D02*
G01Y368089D01*
X354660*
Y377039*
X363210*
G37*
G36*
X352060D02*
G01Y368089D01*
X343510*
Y377039*
X352060*
G37*
G36*
X363210Y388589D02*
G01Y379639D01*
X354660*
Y388589*
X363210*
G37*
G36*
X352060D02*
G01Y379639D01*
X343510*
Y388589*
X352060*
G37*
G36*
X354610Y1512639D02*
G01Y1503689D01*
X346060*
Y1512639*
X354610*
G37*
G36*
X343460D02*
G01Y1503689D01*
X334910*
Y1512639*
X343460*
G37*
G36*
X354610Y1524189D02*
G01Y1515239D01*
X346060*
Y1524189*
X354610*
G37*
G36*
X343460D02*
G01Y1515239D01*
X334910*
Y1524189*
X343460*
G37*
G36*
X-145174Y377139D02*
G01Y368189D01*
X-153724*
Y377139*
X-145174*
G37*
G36*
Y388689D02*
G01Y379739D01*
X-153724*
Y388689*
X-145174*
G37*
G36*
X-168024Y377139D02*
G01Y368189D01*
X-176574*
Y377139*
X-168024*
G37*
G36*
X-179174D02*
G01Y368189D01*
X-187724*
Y377139*
X-179174*
G37*
G36*
X-168024Y388689D02*
G01Y379739D01*
X-176574*
Y388689*
X-168024*
G37*
G36*
X-179174D02*
G01Y379739D01*
X-187724*
Y388689*
X-179174*
G37*
G36*
X-174524Y1513139D02*
G01Y1504189D01*
X-183074*
Y1513139*
X-174524*
G37*
G36*
X-185674D02*
G01Y1504189D01*
X-194224*
Y1513139*
X-185674*
G37*
G36*
X-146524D02*
G01Y1504189D01*
X-155074*
Y1513139*
X-146524*
G37*
G36*
X-157674D02*
G01Y1504189D01*
X-166224*
Y1513139*
X-157674*
G37*
G36*
X-174524Y1524689D02*
G01Y1515739D01*
X-183074*
Y1524689*
X-174524*
G37*
G36*
X-185674D02*
G01Y1515739D01*
X-194224*
Y1524689*
X-185674*
G37*
G36*
X-146524D02*
G01Y1515739D01*
X-155074*
Y1524689*
X-146524*
G37*
G36*
X-157674D02*
G01Y1515739D01*
X-166224*
Y1524689*
X-157674*
G37*
G36*
X-99024Y377139D02*
G01Y368189D01*
X-107574*
Y377139*
X-99024*
G37*
G36*
X-110174D02*
G01Y368189D01*
X-118724*
Y377139*
X-110174*
G37*
G36*
X-99024Y388689D02*
G01Y379739D01*
X-107574*
Y388689*
X-99024*
G37*
G36*
X-110174D02*
G01Y379739D01*
X-118724*
Y388689*
X-110174*
G37*
G36*
X-134024Y377139D02*
G01Y368189D01*
X-142574*
Y377139*
X-134024*
G37*
G36*
Y388689D02*
G01Y379739D01*
X-142574*
Y388689*
X-134024*
G37*
G36*
X-102024Y1513139D02*
G01Y1504189D01*
X-110574*
Y1513139*
X-102024*
G37*
G36*
X-113174D02*
G01Y1504189D01*
X-121724*
Y1513139*
X-113174*
G37*
G36*
X-102024Y1524689D02*
G01Y1515739D01*
X-110574*
Y1524689*
X-102024*
G37*
G36*
X-113174D02*
G01Y1515739D01*
X-121724*
Y1524689*
X-113174*
G37*
G36*
X-65924Y377039D02*
G01Y368089D01*
X-74474*
Y377039*
X-65924*
G37*
G36*
X-77074D02*
G01Y368089D01*
X-85624*
Y377039*
X-77074*
G37*
G36*
X-65924Y388589D02*
G01Y379639D01*
X-74474*
Y388589*
X-65924*
G37*
G36*
X-77074D02*
G01Y379639D01*
X-85624*
Y388589*
X-77074*
G37*
G36*
X-74524Y1512639D02*
G01Y1503689D01*
X-83074*
Y1512639*
X-74524*
G37*
G36*
X-85674D02*
G01Y1503689D01*
X-94224*
Y1512639*
X-85674*
G37*
G36*
X-74524Y1524189D02*
G01Y1515239D01*
X-83074*
Y1524189*
X-74524*
G37*
G36*
X-85674D02*
G01Y1515239D01*
X-94224*
Y1524189*
X-85674*
G37*
G36*
X566434Y1591365D02*
G01Y1600315D01*
X574984*
Y1591365*
X566434*
G37*
G36*
Y1579815D02*
G01Y1588765D01*
X574984*
Y1579815*
X566434*
G37*
G36*
X589284Y1591365D02*
G01Y1600315D01*
X597834*
Y1591365*
X589284*
G37*
G36*
X600434D02*
G01Y1600315D01*
X608984*
Y1591365*
X600434*
G37*
G36*
X589284Y1579815D02*
G01Y1588765D01*
X597834*
Y1579815*
X589284*
G37*
G36*
X600434D02*
G01Y1588765D01*
X608984*
Y1579815*
X600434*
G37*
G36*
X595784Y455365D02*
G01Y464315D01*
X604334*
Y455365*
X595784*
G37*
G36*
X606934D02*
G01Y464315D01*
X615484*
Y455365*
X606934*
G37*
G36*
X567784D02*
G01Y464315D01*
X576334*
Y455365*
X567784*
G37*
G36*
X578934D02*
G01Y464315D01*
X587484*
Y455365*
X578934*
G37*
G36*
X595784Y443815D02*
G01Y452765D01*
X604334*
Y443815*
X595784*
G37*
G36*
X606934D02*
G01Y452765D01*
X615484*
Y443815*
X606934*
G37*
G36*
X567784D02*
G01Y452765D01*
X576334*
Y443815*
X567784*
G37*
G36*
X578934D02*
G01Y452765D01*
X587484*
Y443815*
X578934*
G37*
G36*
X520284Y1591365D02*
G01Y1600315D01*
X528834*
Y1591365*
X520284*
G37*
G36*
X531434D02*
G01Y1600315D01*
X539984*
Y1591365*
X531434*
G37*
G36*
X520284Y1579815D02*
G01Y1588765D01*
X528834*
Y1579815*
X520284*
G37*
G36*
X531434D02*
G01Y1588765D01*
X539984*
Y1579815*
X531434*
G37*
G36*
X555284Y1591365D02*
G01Y1600315D01*
X563834*
Y1591365*
X555284*
G37*
G36*
Y1579815D02*
G01Y1588765D01*
X563834*
Y1579815*
X555284*
G37*
G36*
X523284Y455365D02*
G01Y464315D01*
X531834*
Y455365*
X523284*
G37*
G36*
X534434D02*
G01Y464315D01*
X542984*
Y455365*
X534434*
G37*
G36*
X523284Y443815D02*
G01Y452765D01*
X531834*
Y443815*
X523284*
G37*
G36*
X534434D02*
G01Y452765D01*
X542984*
Y443815*
X534434*
G37*
G36*
X487184Y1591465D02*
G01Y1600415D01*
X495734*
Y1591465*
X487184*
G37*
G36*
X498334D02*
G01Y1600415D01*
X506884*
Y1591465*
X498334*
G37*
G36*
X487184Y1579915D02*
G01Y1588865D01*
X495734*
Y1579915*
X487184*
G37*
G36*
X498334D02*
G01Y1588865D01*
X506884*
Y1579915*
X498334*
G37*
G36*
X495784Y455865D02*
G01Y464815D01*
X504334*
Y455865*
X495784*
G37*
G36*
X506934D02*
G01Y464815D01*
X515484*
Y455865*
X506934*
G37*
G36*
X495784Y444315D02*
G01Y453265D01*
X504334*
Y444315*
X495784*
G37*
G36*
X506934D02*
G01Y453265D01*
X515484*
Y444315*
X506934*
G37*
G36*
X137300Y1591365D02*
G01Y1600315D01*
X145850*
Y1591365*
X137300*
G37*
G36*
Y1579815D02*
G01Y1588765D01*
X145850*
Y1579815*
X137300*
G37*
G36*
X160150Y1591365D02*
G01Y1600315D01*
X168700*
Y1591365*
X160150*
G37*
G36*
X171300D02*
G01Y1600315D01*
X179850*
Y1591365*
X171300*
G37*
G36*
X160150Y1579815D02*
G01Y1588765D01*
X168700*
Y1579815*
X160150*
G37*
G36*
X171300D02*
G01Y1588765D01*
X179850*
Y1579815*
X171300*
G37*
G36*
X166650Y455365D02*
G01Y464315D01*
X175200*
Y455365*
X166650*
G37*
G36*
X177800D02*
G01Y464315D01*
X186350*
Y455365*
X177800*
G37*
G36*
X138650D02*
G01Y464315D01*
X147200*
Y455365*
X138650*
G37*
G36*
X149800D02*
G01Y464315D01*
X158350*
Y455365*
X149800*
G37*
G36*
X166650Y443815D02*
G01Y452765D01*
X175200*
Y443815*
X166650*
G37*
G36*
X177800D02*
G01Y452765D01*
X186350*
Y443815*
X177800*
G37*
G36*
X138650D02*
G01Y452765D01*
X147200*
Y443815*
X138650*
G37*
G36*
X149800D02*
G01Y452765D01*
X158350*
Y443815*
X149800*
G37*
G36*
X91150Y1591365D02*
G01Y1600315D01*
X99700*
Y1591365*
X91150*
G37*
G36*
X102300D02*
G01Y1600315D01*
X110850*
Y1591365*
X102300*
G37*
G36*
X91150Y1579815D02*
G01Y1588765D01*
X99700*
Y1579815*
X91150*
G37*
G36*
X102300D02*
G01Y1588765D01*
X110850*
Y1579815*
X102300*
G37*
G36*
X126150Y1591365D02*
G01Y1600315D01*
X134700*
Y1591365*
X126150*
G37*
G36*
Y1579815D02*
G01Y1588765D01*
X134700*
Y1579815*
X126150*
G37*
G36*
X94150Y455365D02*
G01Y464315D01*
X102700*
Y455365*
X94150*
G37*
G36*
X105300D02*
G01Y464315D01*
X113850*
Y455365*
X105300*
G37*
G36*
X94150Y443815D02*
G01Y452765D01*
X102700*
Y443815*
X94150*
G37*
G36*
X105300D02*
G01Y452765D01*
X113850*
Y443815*
X105300*
G37*
G36*
X58050Y1591465D02*
G01Y1600415D01*
X66600*
Y1591465*
X58050*
G37*
G36*
X69200D02*
G01Y1600415D01*
X77750*
Y1591465*
X69200*
G37*
G36*
X58050Y1579915D02*
G01Y1588865D01*
X66600*
Y1579915*
X58050*
G37*
G36*
X69200D02*
G01Y1588865D01*
X77750*
Y1579915*
X69200*
G37*
G36*
X66650Y455865D02*
G01Y464815D01*
X75200*
Y455865*
X66650*
G37*
G36*
X77800D02*
G01Y464815D01*
X86350*
Y455865*
X77800*
G37*
G36*
X66650Y444315D02*
G01Y453265D01*
X75200*
Y444315*
X66650*
G37*
G36*
X77800D02*
G01Y453265D01*
X86350*
Y444315*
X77800*
G37*
G54D10*
G55*
X-222440Y19685D03*
Y1948818*
X643700Y19685*
Y1948818*
G54D96*
G55*
X19283Y310682D03*
X25900Y1725100*
X57400Y211300*
X56900Y240000*
X56600Y195000*
X32700Y256900*
X63000Y267700*
X39200Y347200*
X81400Y533900*
X78400Y591000*
X49600Y576900*
X61400Y676800*
X57400*
X64100Y912800*
X77002Y1137897*
X32900Y1664200*
X96100Y533900*
X124900Y588604*
X120800*
X93065Y597471*
X97265*
X92465Y610371*
X95200Y665700*
X110900Y884800*
X102600*
X119300*
X122529Y955744*
X117529*
X112529*
X100500Y1423700*
X91500*
X83500Y1465200*
X105000Y1423700*
X107500Y1490200*
X170600Y532500*
X155600Y532400*
X158000Y578600*
X170200Y627100*
X180365Y645771*
X137765Y662071*
X154500Y687200*
X149500Y711700*
X147900Y1003100*
X152100Y1003200*
X163500Y997700*
X159500*
X143800Y1003200*
X135000Y1411804*
X134700Y1404004*
X137500Y1443700*
G54D11*
G55*
X-181139Y20007D03*
X-180444Y1947256*
X601704Y21248*
X602399Y1948497*
G54D95*
G55*
X29100Y321300D03*
X30100Y1083600*
X18600Y1644300*
X18400Y1720700*
X20200Y1692800*
X56900Y155300*
Y163300*
Y179300*
Y159300*
Y175300*
X46500Y213400*
X57800Y217000*
X56900Y199300*
X32800Y272300*
X70800Y431300*
X61000Y577200*
X78556Y690465*
X80700Y686400*
X45400Y916400*
X68700Y999800*
X49400Y1769800*
X88303Y61502*
X85800Y71500*
X117900Y437500*
X125956Y692165*
X125856Y688065*
Y683665*
X112900Y670600*
X83996Y848500*
Y844100*
Y852900*
X84000Y865700*
Y857200*
Y861500*
X111900Y1408200*
X91300Y1451000*
X109700Y1425900*
X91300Y1439000*
X84300Y1484000*
X128800Y1482000*
X159900Y545600*
X162700Y622700*
X152329Y615065*
X171800Y701100*
X152096Y1415000*
X140500Y1458400*
X152100Y1423400*
X152096Y1419200*
X190800Y439500*
G54D12*
G55*
X29921Y24803D03*
Y111417*
Y458031*
Y544646*
Y717874*
Y804488*
X30000Y1164000*
X29921Y1250630*
Y1423858*
Y1510472*
Y1857086*
Y1943701*
G54D30*
G55*
X28000Y1769900D03*
X75700Y71500*
X58200Y662300*
Y657600*
X48700Y1764700*
X110200Y769100*
Y764100*
X99700Y1058400*
Y1053700*
X182300Y1652700*
Y1648000*
X141847Y1878698*
X141800Y1883700*
G54D58*
G55*
X22900Y397800D03*
Y418300*
X19100Y667000*
X81100Y398500*
X47700Y397800*
X81100Y419000*
X47700Y418300*
X43900Y667000*
X73600Y798400*
X63700Y1090600*
X36600Y1551500*
X61400*
X113100Y88500*
X105900Y398500*
Y419000*
X98400Y798400*
X88500Y1090600*
X137900Y88500*
X185300Y397900*
X160500*
X185200Y356700*
X160400*
X185400Y376900*
X160600*
X185300Y418400*
X160500*
X184900Y1531500*
X160100*
X185000Y1551600*
X160200*
G54D52*
G55*
X21350Y1781000D03*
X77953Y54502*
X71650Y584000*
X58350*
X45050Y593000*
X58350*
X81850Y715400*
X81350Y740400*
X60150Y1011800*
X73450*
X64450Y1032100*
X77750*
X34650Y1781000*
X91253Y54502*
X95850Y68500*
X109150*
X95150Y715400*
X94650Y740400*
G54D40*
G55*
X71802Y52947D03*
X71400Y68154*
X75200Y737900*
X75700Y715500*
X53800Y1009500*
X103500Y593900*
X146365Y607721*
G54D13*
G55*
X15906Y48110D03*
Y58110*
Y68110*
Y78110*
Y88110*
Y481339*
Y491339*
Y501339*
Y511339*
Y521339*
Y741181*
Y751181*
Y761181*
Y771181*
Y781181*
Y1187323*
Y1197323*
Y1207323*
Y1217323*
Y1227323*
Y1447165*
Y1457165*
Y1467165*
Y1477165*
Y1487165*
Y1880394*
Y1890394*
Y1900394*
Y1910394*
Y1920394*
X128937Y1778819*
X118937*
X165000Y1390500*
Y1380500*
Y1370500*
X138937Y1778819*
G54D94*
G55*
X30300Y1787800D03*
X64500Y573000*
X71200Y1144500*
X81900Y966200*
X87000Y1143000*
X94800Y1431500*
Y1434900*
Y1442800*
X163400Y549300*
X144300Y695500*
X133300Y1432000*
G54D14*
G55*
X27559Y157480D03*
Y629921*
X17716Y1338583*
X27559Y1811023*
X179134Y78740*
X179133Y570866*
X179134Y1161417*
Y1889764*
G54D41*
G55*
X47244Y68110D03*
Y501338*
Y761181*
Y1207323*
Y1467165*
Y1900393*
G54D50*
G55*
X72000Y473548D03*
Y491452*
X90000Y473548*
Y491452*
X176000Y473048*
Y490952*
X158000Y473048*
Y490952*
G54D28*
G55*
X30000Y570800D03*
X24300Y1106000*
X18600Y1640200*
X19900Y1769600*
X67300Y63500*
X56900Y171300*
Y183300*
Y167300*
Y187300*
X57800Y221000*
X46500Y217400*
X32682Y264217*
X56900Y280000*
X78544Y694635*
X80000Y682200*
X65300Y730000*
X68700Y1004300*
X59600Y1020600*
X72300Y1025400*
X72400Y1020900*
X38000Y1096000*
X68800Y1175100*
X30700Y1774400*
X35000Y1788200*
X98700Y549600*
X83700Y569900*
X91300Y671000*
X115600Y660200*
X104900Y662200*
X87800Y707900*
X86300Y733400*
X104100Y1408100*
X129800Y1428300*
X91300Y1446500*
X109700Y1421600*
X150100Y430800*
X145300Y568000*
X152800Y587000*
X162700Y626700*
X174300Y624300*
X148004Y1394000*
X140500Y1466400*
Y1462400*
X140200Y1453300*
X157300Y1458000*
G54D91*
G55*
X24100Y690900D03*
X28900*
X74100Y576200*
X65635Y693906*
X70535*
X82000Y708200*
X72200Y711000*
X67200*
X70800Y981400*
X64200Y1004100*
X81398Y1137753*
X92300Y878454*
X87500*
X94000Y962800*
X103500Y979800*
X129900Y992500*
X140400Y572400*
X158535Y609679*
G54D87*
G55*
X26700Y1787800D03*
X60900Y573000*
X78300Y966200*
X67600Y1144500*
X83400Y1143000*
X91200Y1431500*
Y1434900*
X129700Y1432000*
X91200Y1442800*
X159800Y549300*
X140700Y695500*
G54D60*
G55*
X70202Y1138347D03*
Y1125047*
X41600Y1767550*
Y1754250*
X88502Y1136247*
Y1122947*
G54D18*
G55*
X80709Y119409D03*
Y329409*
X149606Y119409*
Y329409*
G54D15*
G55*
X31299Y230866D03*
Y220866*
Y210866*
Y338563*
Y358563*
Y348563*
Y903917*
Y923917*
Y913917*
Y1054587*
Y1044587*
Y1064587*
Y1619941*
Y1609941*
Y1629941*
Y1757638*
Y1747638*
Y1737638*
G54D51*
G55*
X73900Y550100D03*
X132735Y593429*
X125835Y593629*
X92971Y617335*
X131935Y601929*
X105000Y603200*
X101900Y654100*
X117100Y1430100*
X136771Y548521*
X144329Y598765*
X140135Y593229*
X160700Y615900*
X151029Y627565*
X139929Y604165*
X156700Y626800*
X179000Y706500*
X147600Y994600*
X154000Y994500*
X142000*
G54D93*
G55*
X35000Y581300D03*
X58100Y1030800*
X87400Y574100*
X149500Y578600*
X164600Y608500*
X150500Y699200*
G54D53*
G55*
X89435Y642629D03*
Y635029*
X89500Y1461700*
Y1469300*
X172100Y549100*
Y541500*
X170100Y607600*
Y615200*
X152265Y608971*
Y601371*
X167000Y1457700*
Y1465300*
G54D61*
G55*
X80200Y1477500D03*
X107600Y558300*
X115200*
X87800Y1477500*
X106770Y1480640*
X99170*
X183700Y1606500*
X180700Y1641000*
X191300Y1606500*
X188300Y1641000*
G54D32*
G55*
X27471Y262553D03*
X19721*
X23596Y255053*
X24925Y305350*
X28800Y312850*
X27625Y1649050*
X27292Y1714868*
X19542*
X23417Y1707368*
X32675Y305350*
X54817Y902368*
X58692Y909868*
X50942*
X78752Y1613297*
Y1619703*
X35375Y1649050*
X31500Y1641550*
X131525Y722550*
X109252Y1613297*
Y1619703*
X141625Y682250*
X149375*
X145500Y689750*
X139275Y722550*
X135400Y730050*
X148025Y1401454*
X155775*
X151900Y1408954*
X165494Y1437469*
X173244*
X169369Y1444969*
X138694Y1422269*
X146444*
X142569Y1429769*
X137752Y1613297*
Y1619703*
X165252Y1613297*
Y1619703*
G54D43*
G55*
X80709Y139409D03*
Y309409*
X149606Y139409*
Y309409*
G54D34*
G55*
X72200Y86200D03*
X72602Y757897*
X63700Y1050100*
X99000Y86200*
X99402Y757897*
X90500Y1050100*
G54D27*
G55*
X24100Y685300D03*
X28900*
X74100Y570600*
X82000Y702600*
X65635Y688306*
X70535*
X72200Y705400*
X67200*
X70800Y975800*
X64200Y998500*
X81398Y1132153*
X92300Y872854*
X87500*
X94000Y957200*
X103500Y974200*
X129900Y986900*
X140400Y566800*
X158535Y604079*
G54D90*
G55*
X78247Y61398D03*
X50600Y252800*
X34400Y294300*
X67900Y591000*
X71000Y986600*
X62000Y1025000*
X111300Y380100*
X85929Y533679*
X101500Y986000*
Y990800*
X89200Y1455500*
X101200Y1474500*
X160300Y532100*
X160100Y553300*
X176421Y613535*
X154700Y1462500*
G54D86*
G55*
X35000Y584900D03*
X58100Y1034400*
X87400Y577700*
X149500Y582200*
X164600Y612100*
X150500Y702800*
G54D62*
G55*
X78900Y1498700D03*
Y1523500*
X124298Y1908303*
Y1883503*
X145798Y1151303*
Y1126503*
G54D42*
G55*
X93206Y677415D03*
Y682415*
Y687415*
Y692415*
X113306*
Y687415*
Y682415*
Y677415*
G54D80*
G55*
X171370Y634819D03*
X159800*
X171370Y645839*
X159800*
G54D35*
G55*
X27900Y246900D03*
X25300Y328500*
X16200Y1657100*
X27200*
X15800Y1699200*
X26800*
X38900Y246900*
X36300Y328500*
X124696Y1392300*
X106000Y1387500*
X117000*
X135696Y1392300*
X154000Y1387500*
X143000*
G54D72*
G55*
X27700Y1106000D03*
X22000Y1640200*
X23300Y1769600*
X70700Y63500*
X60300Y171300*
Y183300*
Y167300*
Y187300*
X61200Y221000*
X49900Y217400*
X36082Y264217*
X60300Y280000*
X33400Y570800*
X68700Y730000*
X72100Y1004300*
X63000Y1020600*
X75700Y1025400*
X75800Y1020900*
X41400Y1096000*
X72200Y1175100*
X34100Y1774400*
X38400Y1788200*
X102100Y549600*
X87100Y569900*
X81944Y694635*
X94700Y671000*
X119000Y660200*
X108300Y662200*
X83400Y682200*
X91200Y707900*
X89700Y733400*
X107500Y1408100*
X94700Y1446500*
X113100Y1421600*
X153500Y430800*
X148700Y568000*
X156200Y587000*
X166100Y626700*
X177700Y624300*
X151404Y1394000*
X133200Y1428300*
X143900Y1466400*
Y1462400*
X143600Y1453300*
X160700Y1458000*
G54D44*
G55*
X80709Y161889D03*
Y171889*
Y181889*
Y191889*
Y204409*
Y214409*
Y224409*
Y234409*
Y244409*
Y256929*
Y266929*
Y276929*
Y286929*
X110709Y161889*
Y171889*
X100709Y161889*
Y171889*
X90709Y161889*
Y171889*
X110709Y181889*
Y191889*
X100709Y181889*
Y191889*
X90709Y181889*
Y191889*
X110709Y204409*
Y214409*
Y224409*
Y234409*
Y244409*
X100709Y204409*
Y214409*
Y224409*
Y234409*
Y244409*
X90709Y204409*
Y214409*
Y224409*
Y234409*
Y244409*
X110709Y256929*
Y266929*
X100709Y256929*
Y266929*
X90709Y256929*
Y266929*
X110709Y276929*
Y286929*
X100709Y276929*
Y286929*
X90709Y276929*
Y286929*
X179606Y161889*
Y171889*
X169606Y161889*
Y171889*
X159606Y161889*
Y171889*
X149606Y161889*
Y171889*
X179606Y181889*
Y191889*
X169606Y181889*
Y191889*
X159606Y181889*
Y191889*
X149606Y181889*
Y191889*
X179606Y204409*
Y214409*
Y224409*
Y234409*
Y244409*
X169606Y204409*
Y214409*
Y224409*
Y234409*
Y244409*
X159606Y204409*
Y214409*
Y224409*
Y234409*
Y244409*
X149606Y204409*
Y214409*
Y224409*
Y234409*
Y244409*
X179606Y256929*
Y266929*
X169606Y256929*
Y266929*
X159606Y256929*
Y266929*
X149606Y256929*
Y266929*
X179606Y276929*
Y286929*
X169606Y276929*
Y286929*
X159606Y276929*
Y286929*
X149606Y276929*
Y286929*
G54D63*
G55*
X71250Y1613297D03*
Y1619703*
X101750Y1613297*
Y1619703*
X130250Y1613297*
Y1619703*
X157750Y1613297*
Y1619703*
G54D33*
G55*
X134709Y710500D03*
X117291*
G54D31*
G55*
X24368Y1093083D03*
X31868Y1089208*
Y1096958*
X112018Y566991*
Y574741*
X104518Y570866*
X112018Y1255968*
Y1263718*
X104518Y1259843*
G54D45*
G55*
X47498Y238899D03*
X52200Y238900*
X62700Y254200*
X45100Y577300*
X81500Y727600*
X63202Y1128347*
X103900Y476600*
X96300Y557700*
X129065Y673094*
X123465*
X124900Y722600*
X94500Y976700*
X130800Y975800*
X146700Y476700*
X163300Y696500*
X144300Y1111300*
X149002Y1111347*
X133500Y1471200*
G54D36*
G55*
X81300Y71500D03*
X63800Y662300*
Y657600*
X54300Y1764700*
X33600Y1769900*
X115800Y769100*
Y764100*
X105300Y1058400*
Y1053700*
X147447Y1878698*
X147400Y1883700*
X187900Y1652700*
Y1648000*
G54D81*
G55*
X180465Y631371D03*
Y634971*
G54D54*
G55*
X73403Y633502D03*
Y606702*
X122097Y1125298*
Y1152098*
X98497Y1883198*
Y1909998*
G54D16*
G55*
X18600Y249100D03*
X27900Y269471*
X20010Y302982*
X11000Y578000*
X27300Y593000*
X27100Y578100*
X24500Y1102000*
X20056Y1774189*
X43900Y137200*
X36200Y318700*
X63200Y385100*
X62400Y430600*
X62900Y412900*
X61700Y421900*
X70900Y427200*
X66000Y510500*
X77400Y536300*
X70400Y565500*
X49665Y642933*
X43337Y650145*
X37000Y605000*
X57200Y667884*
X65000Y775000*
Y766000*
X43100Y866100*
X76500Y900500*
X65900Y900000*
X64100Y904800*
X73000Y966000*
X66900Y969100*
X60000Y966800*
X81500Y985900*
X51500Y974100*
X37200Y1091700*
X52100Y1132700*
X71000Y1232600*
X33000Y1575000*
X53300Y1609200*
X64400Y1605900*
X62300Y1641300*
X59500Y1627500*
X32900Y1656300*
X61500Y1716500*
X72500Y1717000*
Y1699000*
X33000Y1718500*
X32949Y1709451*
X79000Y1766500*
X71500Y1760000*
X72500Y1733000*
X81000Y1802000*
X73000Y1813000*
X72000Y1798000*
X57000Y1805500*
X75500Y1838500*
X73000Y1847000*
X72500Y1830000*
X66000Y1917000*
X118500Y442000*
X122500Y429000*
X125100Y408900*
X115000Y486100*
X106500Y469500*
X115500Y476700*
X96900Y541600*
X99800Y545600*
X120800Y598700*
X112018Y584900*
X106338Y580496*
X118565Y592846*
X83619Y581742*
X82900Y574500*
X101800Y557400*
X96500Y567600*
X99578Y605771*
X93063Y629134*
X94545Y601197*
X91463Y623143*
X122088Y665912*
X119300Y656600*
X111400Y658500*
X86060Y695200*
X86000Y689900*
X125202Y657500*
X129000Y653600*
X95500Y728000*
X105500Y732000*
X117500Y724500*
X109000Y809500*
X119300Y837000*
X92400Y848900*
X103400Y838300*
X98700Y877100*
X92800Y865300*
X111100Y876700*
X92700Y858100*
X108200Y953500*
X112984Y946835*
X120054Y945600*
X130903Y958178*
X94500Y950500*
X110400Y997850*
X119080Y992900*
X127700Y998400*
X87600Y965900*
X90542Y987958*
X97958Y966958*
X103500Y966500*
X130900Y1003400*
X91500Y1030500*
X85500Y1009500*
X128500Y1076800*
X122862Y1385500*
X129000Y1416425*
X99500Y1407500*
X100000Y1443000*
X101000Y1460750*
X113024Y1452079*
X117122Y1448001*
X117195Y1456070*
X121338Y1452021*
X117024Y1452000*
X100200Y1433800*
X99700Y1450700*
X103000Y1429500*
X123000Y1431300*
X126975Y1435400*
X127300Y1468800*
X111833Y1469667*
X117500Y1519500*
X104333Y1498167*
X130180Y1486680*
X98000Y1564700*
X89500Y1610000*
X120500Y1606000*
X98500Y1717000*
Y1696500*
X99000Y1707000*
X109500Y1719500*
X110000Y1709500*
X109500Y1699000*
X119500Y1710110*
Y1696610*
X86500Y1713610*
Y1700110*
X119500Y1725110*
X111500Y1768500*
X108500Y1727000*
X117500Y1732000*
X119500Y1760000*
X97500Y1775500*
X86500Y1726000*
X87000Y1774110*
X119500Y1747110*
X110500Y1801000*
X88500Y1785000*
X97500Y1796000*
X98000Y1786000*
X86500Y1793110*
X108268Y1777300*
X107768Y1789110*
X120000Y1811500*
X119500Y1796500*
X84000Y1869600*
X114000Y1843500*
X97000Y1850500*
X120500Y1836500*
Y1850500*
X108500Y1851610*
X85100Y1844500*
X85700Y1852300*
X82000Y1915000*
X162612Y438169*
X143400Y408200*
X144400Y470800*
X149000Y522500*
X174800Y532200*
X151500Y533000*
X164200Y541900*
X149500Y574600*
X145230Y571700*
X135200Y566400*
X176300Y608635*
X157200Y620800*
X146663Y634051*
X148595Y618300*
X151335Y640400*
X145200Y644600*
X163100Y604717*
X179017Y620013*
X174100Y652900*
X153200Y653200*
X173000Y691000*
X142000Y701000*
X158500Y695000*
X145500Y675000*
X145000Y711750*
X167600Y703300*
X160500Y916500*
X133500Y953000*
X139500Y951500*
X143100Y1007100*
X162000Y1027000*
X178500Y1268500*
X159774Y1414374*
X136100Y1463900*
X134400Y1454300*
X133000Y1447600*
X165500Y1450600*
X138000Y1448500*
X142400Y1499900*
X136500Y1481425*
X148500Y1479500*
X136500Y1651000*
X139000Y1696500*
Y1712500*
X181500Y1716500*
X158500*
X167500Y1716000*
X182000Y1704000*
X168500Y1705000*
X158500*
X163000Y1697000*
X174268Y1697110*
X152000*
Y1710610*
Y1725610*
X138500Y1727500*
X182000Y1726000*
X183600Y1765100*
X162500Y1773000*
X152500Y1771110*
X173268Y1776000*
X139000Y1800500*
X138000Y1824000*
X169000Y1781500*
X156500Y1782000*
X155500Y1798500*
X166500Y1798000*
X179000Y1798500*
X162000Y1790000*
X172768Y1790110*
X152000*
X137000Y1877500*
X139000Y1851000*
X138500Y1839500*
X161500Y1852500*
X183100Y1838300*
X173000Y1852610*
X151500Y1851110*
X139861Y1889461*
X189928Y435800*
X197500Y481500*
X186000Y1133000*
X189000Y1432000*
X184500Y1696500*
X185000Y1738500*
X185500Y1804500*
X186000Y1790000*
X185000Y1852500*
G54D92*
G55*
X96457Y1773425D03*
G54D89*
G55*
X19283Y307282D03*
X25900Y1721700*
X57400Y207900*
X56900Y236600*
X56600Y191600*
X32700Y253500*
X63000Y264300*
X39200Y343800*
X81400Y530500*
X78400Y587600*
X49600Y573500*
X61400Y673400*
X57400*
X64100Y909400*
X77002Y1134497*
X32900Y1660800*
X96100Y530500*
X124900Y585204*
X120800*
X93065Y594071*
X97265*
X92465Y606971*
X95200Y662300*
X110900Y881400*
X102600*
X119300*
X122529Y952344*
X117529*
X112529*
X100500Y1420300*
X91500*
X83500Y1461800*
X105000Y1420300*
X107500Y1486800*
X170600Y529100*
X155600Y529000*
X158000Y575200*
X170200Y623700*
X180365Y642371*
X137765Y658671*
X154500Y683800*
X149500Y708300*
X147900Y999700*
X152100Y999800*
X163500Y994300*
X159500*
X143800Y999800*
X135000Y1408404*
X134700Y1400604*
X137500Y1440300*
G54D88*
G55*
X22000Y1644300D03*
X21800Y1720700*
X23600Y1692800*
X60300Y155300*
Y163300*
Y179300*
Y159300*
Y175300*
X49900Y213400*
X61200Y217000*
X60300Y199300*
X36200Y272300*
X32500Y321300*
X74200Y431300*
X64400Y577200*
X48800Y916400*
X72100Y999800*
X33500Y1083600*
X52800Y1769800*
X91703Y61502*
X89200Y71500*
X121300Y437500*
X81956Y690465*
X84100Y686400*
X129356Y692165*
X129256Y688065*
Y683665*
X116300Y670600*
X87396Y848500*
Y844100*
Y852900*
X87400Y865700*
Y857200*
Y861500*
X115300Y1408200*
X94700Y1451000*
X113100Y1425900*
X94700Y1439000*
X87700Y1484000*
X132200Y1482000*
X163300Y545600*
X166100Y622700*
X155729Y615065*
X175200Y701100*
X155496Y1415000*
X143900Y1458400*
X155500Y1423400*
X155496Y1419200*
X194200Y439500*
G54D55*
G55*
X66875Y674606D03*
X69435*
X71995*
Y681106*
X66875*
G54D82*
G55*
X141100Y1401696D03*
Y1410096*
X158600Y1446404*
Y1438004*
G54D73*
G55*
X116175Y846304D03*
X113620*
X111060*
X108500*
X105940*
X103380*
X100825*
Y868504*
X103380*
X105940*
X108500*
X111060*
X113620*
X116175*
X113960Y985200*
X116520*
X119080*
X121640*
Y963000*
X119080*
X116520*
X113960*
X155825Y732304*
X158380*
X160940*
X163500*
X166060*
X168620*
X171175*
Y710104*
X168620*
X166060*
X163500*
X160940*
X158380*
X155825*
X137340Y959500*
X139900*
X142460*
X145020*
X147580*
X150140*
X152700*
X155260*
Y981700*
X152700*
X150140*
X147580*
X145020*
X142460*
X139900*
X137340*
G54D46*
G55*
X47498Y244499D03*
X52200Y244500*
X62700Y259800*
X45100Y582900*
X81500Y733200*
X63202Y1133947*
X103900Y482200*
X96300Y563300*
X129065Y678694*
X123465*
X124900Y728200*
X94500Y982300*
X130800Y981400*
X146700Y482300*
X163300Y702100*
X144300Y1116900*
X149002Y1116947*
X133500Y1476800*
G54D37*
G55*
X67998Y56503D03*
X67398Y71003*
X61000Y240000*
X61600Y211300*
X60600Y195000*
X54300Y263300*
X58300*
X37200Y256900*
X62600Y249200*
X73700Y543300*
X78600Y574500*
X73900Y558800*
X39000Y581300*
X77200Y705900*
X77000Y730800*
X43400Y896100*
X81398Y1126103*
X63498Y1123803*
X63198Y1142003*
X48300Y1755700*
X116800Y588596*
X128900*
X91300Y573200*
X129335Y662029*
X104900Y662200*
X115600Y660200*
X116300Y670600*
X119600Y831800*
X111200*
X102900Y831796*
X121671Y939756*
X117300Y939700*
X110500*
X131500Y947800*
X123300Y1001300*
X119300*
X114800*
X99000Y979700*
X123000Y1424200*
X127500*
X95500Y1464200*
X118000Y1424200*
X95600Y1423700*
X129000Y1501700*
X125000*
X121000*
X117000*
X113000*
X109000*
X93500Y1479200*
X136779Y543071*
X145300Y582200*
X153500Y570000*
X136679Y557171*
X151335Y635829*
X148435Y653329*
X133535Y662029*
X144235Y653329*
X167700Y699600*
X154500Y702700*
X158500*
X149000Y949200*
X153000*
X157000*
X145000*
X140500Y947800*
X136000*
X139100Y1003100*
X135000Y1003200*
X156631Y1431081*
X160831Y1430281*
X152331Y1431081*
X165400Y1430200*
X151000Y1491200*
X146500*
X142000*
X137000Y1501700*
X133000*
X137900Y1491100*
X148500Y1474100*
G54D83*
G55*
X147500Y1437250D03*
X143625Y1444750*
X151375*
G54D56*
G55*
X51750Y690560D03*
Y688000*
Y685440*
X58250*
Y690560*
X36250*
Y688000*
Y685440*
X42750*
Y690560*
G54D74*
G55*
X113800Y1397140D03*
Y1399700*
Y1402260*
X106400*
Y1399700*
Y1397140*
G54D65*
G55*
X48200Y1760300D03*
X86800Y537800*
X96100*
X98600Y553300*
X107600Y593700*
X112900Y603500*
X170600Y536400*
X160900Y536500*
G54D38*
G55*
X67998Y53103D03*
X67398Y67603*
X61000Y236600*
X61600Y207900*
X60600Y191600*
X54300Y259900*
X58300*
X37200Y253500*
X62600Y245800*
X73700Y539900*
X78600Y571100*
X73900Y555400*
X39000Y577900*
X77200Y702500*
X77000Y727400*
X43400Y892700*
X81398Y1122703*
X63498Y1120403*
X63198Y1138603*
X48300Y1752300*
X116800Y585196*
X128900*
X91300Y569800*
X129335Y658629*
X104900Y658800*
X115600Y656800*
X116300Y667200*
X119600Y828400*
X111200*
X102900Y828396*
X121671Y936356*
X117300Y936300*
X110500*
X131500Y944400*
X123300Y997900*
X119300*
X114800*
X99000Y976300*
X123000Y1420800*
X127500*
X95500Y1460800*
X118000Y1420800*
X95600Y1420300*
X129000Y1498300*
X125000*
X121000*
X117000*
X113000*
X109000*
X93500Y1475800*
X136779Y539671*
X145300Y578800*
X153500Y566600*
X136679Y553771*
X151335Y632429*
X148435Y649929*
X144235*
X133535Y658629*
X154500Y699300*
X167700Y696200*
X158500Y699300*
X149000Y945800*
X153000*
X157000*
X145000*
X140500Y944400*
X136000*
X139100Y999700*
X135000Y999800*
X156631Y1427681*
X160831Y1426881*
X152331Y1427681*
X165400Y1426800*
X151000Y1487800*
X146500*
X142000*
X137000Y1498300*
X133000*
X137900Y1487700*
X148500Y1470700*
G54D29*
G55*
X32359Y1680500D03*
X60641*
G54D47*
G55*
X56200Y252800D03*
X40000Y294300*
X73500Y591000*
X76600Y986600*
X67600Y1025000*
X83847Y61398*
X116900Y380100*
X91529Y533679*
X107100Y986000*
Y990800*
X94800Y1455500*
X106800Y1474500*
X165900Y532100*
X165700Y553300*
X182021Y613535*
X160300Y1462500*
G54D57*
G55*
X49900Y883800D03*
Y894800*
X63800Y986600*
Y975600*
X39000Y1022500*
Y1033500*
X96000Y931000*
Y942000*
X147000Y732000*
Y721000*
G54D84*
G55*
X142300Y1471800D03*
Y1480800*
G54D39*
G55*
X71802Y56547D03*
X71400Y71754*
X75200Y741500*
X75700Y719100*
X53800Y1013100*
X103500Y597500*
X146365Y611321*
G54D66*
G55*
X51800Y1760300D03*
X90400Y537800*
X99700*
X102200Y553300*
X111200Y593700*
X116500Y603500*
X174200Y536400*
X164500Y536500*
G54D75*
G55*
X125000Y1409454D03*
X121125Y1401954*
X128875*
G54D48*
G55*
X69635Y361900D03*
X110735Y361800*
X99365Y361900*
X140465Y361800*
X157835Y1507700*
X187565*
G54D64*
G55*
X63901Y949600D03*
X86699*
G54D67*
G55*
X96457Y1747835D03*
Y1823031*
X178937Y1328740*
X161417Y1747835*
Y1823031*
G54D76*
G55*
X111882Y1461600D03*
X114441*
X117000*
X119559*
X122118*
Y1442400*
X119559*
X117000*
X114441*
X111882*
G54D49*
G55*
X69000Y440000D03*
X74000*
X79000*
X60400Y1575600*
X65400*
X70400*
X75400*
X96500Y439500*
X101500*
X106500*
X111500*
X84000Y440000*
X128500Y1575500*
X93500*
X98500*
X103500*
X108500*
X141000Y439500*
X146000*
X151000*
X156000*
X169000*
X174000*
X179000*
X184000*
X162500Y1575500*
X167500*
X172500*
X177500*
X133500*
X138500*
X143500*
G54D85*
G55*
X161417Y1773425D03*
G54D77*
G55*
X126600Y1457118D03*
Y1454559*
Y1452000*
Y1449441*
Y1446882*
X107400*
Y1449441*
Y1452000*
Y1454559*
Y1457118*
G54D68*
G55*
X89335Y544750D03*
X87370*
X85400*
X83430*
X81465*
Y561050*
X83430*
X85400*
X87370*
X89335*
X108710Y612629*
X110675*
X112645*
X114615*
X116580*
X118550*
X120520*
X122490*
X124455*
X126425*
X128395*
X130360*
Y646029*
X128395*
X126425*
X124455*
X122490*
X120520*
X118550*
X116580*
X114615*
X112645*
X110675*
X108710*
X153135Y542950*
X151170*
X149200*
X147230*
X145265*
Y559250*
X147230*
X149200*
X151170*
X153135*
G54D59*
G55*
X77400Y980050D03*
Y976300*
Y972550*
X88000*
Y976300*
Y980050*
G54D78*
G55*
X117000Y1452000D03*
G54D69*
G55*
X102835Y640154D03*
Y638189*
Y636219*
Y634249*
Y632284*
Y630314*
Y628344*
Y626374*
Y624409*
Y622439*
Y620469*
Y618504*
X136235*
Y620469*
Y622439*
Y624409*
Y626374*
Y628344*
Y630314*
Y632284*
Y634249*
Y636219*
Y638189*
Y640154*
G54D79*
G55*
X150000Y64500D03*
X152500Y1906000*
G54D96*
G55*
X448417Y310682D03*
X455034Y1725100*
X486534Y211300*
X486034Y240000*
X485734Y195000*
X461834Y256900*
X492134Y267700*
X468334Y347200*
X510534Y533900*
X507534Y591000*
X478734Y576900*
X490534Y676800*
X486534*
X493234Y912800*
X506136Y1137897*
X462034Y1664200*
X525234Y533900*
X554034Y588604*
X549934*
X522199Y597471*
X526399*
X521599Y610371*
X524334Y665700*
X540034Y884800*
X531734*
X548434*
X551663Y955744*
X546663*
X541663*
X529634Y1423700*
X520634*
X512634Y1465200*
X534134Y1423700*
X536634Y1490200*
X599734Y532500*
X584734Y532400*
X587134Y578600*
X599334Y627100*
X609499Y645771*
X566899Y662071*
X583634Y687200*
X578634Y711700*
X577034Y1003100*
X581234Y1003200*
X592634Y997700*
X588634*
X572934Y1003200*
X564134Y1411804*
X563834Y1404004*
X566634Y1443700*
G54D95*
G55*
X458234Y321300D03*
X459234Y1083600*
X447734Y1644300*
X447534Y1720700*
X449334Y1692800*
X486034Y155300*
Y163300*
Y179300*
Y159300*
Y175300*
X475634Y213400*
X486934Y217000*
X486034Y199300*
X461934Y272300*
X499934Y431300*
X490134Y577200*
X507690Y690465*
X509834Y686400*
X474534Y916400*
X497834Y999800*
X478534Y1769800*
X517437Y61502*
X514934Y71500*
X547034Y437500*
X555090Y692165*
X554990Y688065*
Y683665*
X542034Y670600*
X513130Y848500*
Y844100*
Y852900*
X513134Y865700*
Y857200*
Y861500*
X541034Y1408200*
X520434Y1451000*
X538834Y1425900*
X520434Y1439000*
X513434Y1484000*
X557934Y1482000*
X589034Y545600*
X591834Y622700*
X581463Y615065*
X600934Y701100*
X581230Y1415000*
X569634Y1458400*
X581234Y1423400*
X581230Y1419200*
X619934Y439500*
G54D12*
G55*
X459055Y24803D03*
Y111417*
Y458031*
Y544646*
Y717874*
Y804488*
X459134Y1164000*
X459055Y1250630*
Y1423858*
Y1510472*
Y1857086*
Y1943701*
G54D30*
G55*
X457134Y1769900D03*
X504834Y71500*
X487334Y662300*
Y657600*
X477834Y1764700*
X539334Y769100*
Y764100*
X528834Y1058400*
Y1053700*
X611434Y1652700*
Y1648000*
X570981Y1878698*
X570934Y1883700*
G54D58*
G55*
X452034Y397800D03*
Y418300*
X448234Y667000*
X510234Y398500*
X476834Y397800*
X510234Y419000*
X476834Y418300*
X473034Y667000*
X502734Y798400*
X492834Y1090600*
X465734Y1551500*
X490534*
X542234Y88500*
X535034Y398500*
Y419000*
X527534Y798400*
X517634Y1090600*
X567034Y88500*
X614434Y397900*
X589634*
X614334Y356700*
X589534*
X614534Y376900*
X589734*
X614434Y418400*
X589634*
X614034Y1531500*
X589234*
X614134Y1551600*
X589334*
G54D52*
G55*
X450484Y1781000D03*
X507087Y54502*
X500784Y584000*
X487484*
X474184Y593000*
X487484*
X510984Y715400*
X510484Y740400*
X489284Y1011800*
X502584*
X493584Y1032100*
X506884*
X463784Y1781000*
X520387Y54502*
X524984Y68500*
X538284*
X524284Y715400*
X523784Y740400*
G54D40*
G55*
X500936Y52947D03*
X500534Y68154*
X504334Y737900*
X504834Y715500*
X482934Y1009500*
X532634Y593900*
X575499Y607721*
G54D13*
G55*
X445040Y48110D03*
Y58110*
Y68110*
Y78110*
Y88110*
Y481339*
Y491339*
Y501339*
Y511339*
Y521339*
Y741181*
Y751181*
Y761181*
Y771181*
Y781181*
Y1187323*
Y1197323*
Y1207323*
Y1217323*
Y1227323*
Y1447165*
Y1457165*
Y1467165*
Y1477165*
Y1487165*
Y1880394*
Y1890394*
Y1900394*
Y1910394*
Y1920394*
X558071Y1778819*
X548071*
X594134Y1390500*
Y1380500*
Y1370500*
X568071Y1778819*
G54D94*
G55*
X459434Y1787800D03*
X493634Y573000*
X500334Y1144500*
X511034Y966200*
X516134Y1143000*
X523934Y1431500*
Y1434900*
Y1442800*
X592534Y549300*
X573434Y695500*
X562434Y1432000*
G54D14*
G55*
X456693Y157480D03*
Y629921*
X446850Y1338583*
X456693Y1811023*
X608268Y78740*
X608267Y570866*
X608268Y1161417*
Y1889764*
G54D41*
G55*
X476378Y68110D03*
Y501338*
Y761181*
Y1207323*
Y1467165*
Y1900393*
G54D50*
G55*
X501134Y473548D03*
Y491452*
X519134Y473548*
Y491452*
X605134Y473048*
Y490952*
X587134Y473048*
Y490952*
G54D28*
G55*
X459134Y570800D03*
X453434Y1106000*
X447734Y1640200*
X449034Y1769600*
X496434Y63500*
X486034Y171300*
Y183300*
Y167300*
Y187300*
X486934Y221000*
X475634Y217400*
X461816Y264217*
X486034Y280000*
X507678Y694635*
X509134Y682200*
X494434Y730000*
X497834Y1004300*
X488734Y1020600*
X501434Y1025400*
X501534Y1020900*
X467134Y1096000*
X497934Y1175100*
X459834Y1774400*
X464134Y1788200*
X527834Y549600*
X512834Y569900*
X520434Y671000*
X544734Y660200*
X534034Y662200*
X516934Y707900*
X515434Y733400*
X533234Y1408100*
X558934Y1428300*
X520434Y1446500*
X538834Y1421600*
X579234Y430800*
X574434Y568000*
X581934Y587000*
X591834Y626700*
X603434Y624300*
X577138Y1394000*
X569634Y1466400*
Y1462400*
X569334Y1453300*
X586434Y1458000*
G54D91*
G55*
X453234Y690900D03*
X458034*
X503234Y576200*
X494769Y693906*
X499669*
X511134Y708200*
X501334Y711000*
X496334*
X499934Y981400*
X493334Y1004100*
X510532Y1137753*
X521434Y878454*
X516634*
X523134Y962800*
X532634Y979800*
X559034Y992500*
X569534Y572400*
X587669Y609679*
G54D87*
G55*
X455834Y1787800D03*
X490034Y573000*
X507434Y966200*
X496734Y1144500*
X512534Y1143000*
X520334Y1431500*
Y1434900*
X558834Y1432000*
X520334Y1442800*
X588934Y549300*
X569834Y695500*
G54D60*
G55*
X499336Y1138347D03*
Y1125047*
X470734Y1767550*
Y1754250*
X517636Y1136247*
Y1122947*
G54D18*
G55*
X509843Y119409D03*
Y329409*
X578740Y119409*
Y329409*
G54D15*
G55*
X460433Y230866D03*
Y220866*
Y210866*
Y338563*
Y358563*
Y348563*
Y903917*
Y923917*
Y913917*
Y1054587*
Y1044587*
Y1064587*
Y1619941*
Y1609941*
Y1629941*
Y1757638*
Y1747638*
Y1737638*
G54D51*
G55*
X503034Y550100D03*
X561869Y593429*
X554969Y593629*
X522105Y617335*
X561069Y601929*
X534134Y603200*
X531034Y654100*
X546234Y1430100*
X565905Y548521*
X573463Y598765*
X569269Y593229*
X589834Y615900*
X580163Y627565*
X569063Y604165*
X585834Y626800*
X608134Y706500*
X576734Y994600*
X583134Y994500*
X571134*
G54D93*
G55*
X464134Y581300D03*
X487234Y1030800*
X516534Y574100*
X578634Y578600*
X593734Y608500*
X579634Y699200*
G54D53*
G55*
X518569Y642629D03*
Y635029*
X518634Y1461700*
Y1469300*
X601234Y549100*
Y541500*
X599234Y607600*
Y615200*
X581399Y608971*
Y601371*
X596134Y1457700*
Y1465300*
G54D61*
G55*
X509334Y1477500D03*
X536734Y558300*
X544334*
X516934Y1477500*
X535904Y1480640*
X528304*
X612834Y1606500*
X609834Y1641000*
X620434Y1606500*
X617434Y1641000*
G54D32*
G55*
X456605Y262553D03*
X448855*
X452730Y255053*
X454059Y305350*
X457934Y312850*
X456759Y1649050*
X456426Y1714868*
X448676*
X452551Y1707368*
X461809Y305350*
X483951Y902368*
X487826Y909868*
X480076*
X507886Y1613297*
Y1619703*
X464509Y1649050*
X460634Y1641550*
X560659Y722550*
X538386Y1613297*
Y1619703*
X570759Y682250*
X578509*
X574634Y689750*
X568409Y722550*
X564534Y730050*
X577159Y1401454*
X584909*
X581034Y1408954*
X594628Y1437469*
X602378*
X598503Y1444969*
X567828Y1422269*
X575578*
X571703Y1429769*
X566886Y1613297*
Y1619703*
X594386Y1613297*
Y1619703*
G54D43*
G55*
X509843Y139409D03*
Y309409*
X578740Y139409*
Y309409*
G54D34*
G55*
X501334Y86200D03*
X501736Y757897*
X492834Y1050100*
X528134Y86200*
X528536Y757897*
X519634Y1050100*
G54D27*
G55*
X453234Y685300D03*
X458034*
X503234Y570600*
X511134Y702600*
X494769Y688306*
X499669*
X501334Y705400*
X496334*
X499934Y975800*
X493334Y998500*
X510532Y1132153*
X521434Y872854*
X516634*
X523134Y957200*
X532634Y974200*
X559034Y986900*
X569534Y566800*
X587669Y604079*
G54D90*
G55*
X507381Y61398D03*
X479734Y252800*
X463534Y294300*
X497034Y591000*
X500134Y986600*
X491134Y1025000*
X540434Y380100*
X515063Y533679*
X530634Y986000*
Y990800*
X518334Y1455500*
X530334Y1474500*
X589434Y532100*
X589234Y553300*
X605555Y613535*
X583834Y1462500*
G54D86*
G55*
X464134Y584900D03*
X487234Y1034400*
X516534Y577700*
X578634Y582200*
X593734Y612100*
X579634Y702800*
G54D62*
G55*
X508034Y1498700D03*
Y1523500*
X553432Y1908303*
Y1883503*
X574932Y1151303*
Y1126503*
G54D42*
G55*
X522340Y677415D03*
Y682415*
Y687415*
Y692415*
X542440*
Y687415*
Y682415*
Y677415*
G54D80*
G55*
X600504Y634819D03*
X588934*
X600504Y645839*
X588934*
G54D35*
G55*
X457034Y246900D03*
X454434Y328500*
X445334Y1657100*
X456334*
X444934Y1699200*
X455934*
X468034Y246900*
X465434Y328500*
X553830Y1392300*
X535134Y1387500*
X546134*
X564830Y1392300*
X583134Y1387500*
X572134*
G54D72*
G55*
X456834Y1106000D03*
X451134Y1640200*
X452434Y1769600*
X499834Y63500*
X489434Y171300*
Y183300*
Y167300*
Y187300*
X490334Y221000*
X479034Y217400*
X465216Y264217*
X489434Y280000*
X462534Y570800*
X497834Y730000*
X501234Y1004300*
X492134Y1020600*
X504834Y1025400*
X504934Y1020900*
X470534Y1096000*
X501334Y1175100*
X463234Y1774400*
X467534Y1788200*
X531234Y549600*
X516234Y569900*
X511078Y694635*
X523834Y671000*
X548134Y660200*
X537434Y662200*
X512534Y682200*
X520334Y707900*
X518834Y733400*
X536634Y1408100*
X523834Y1446500*
X542234Y1421600*
X582634Y430800*
X577834Y568000*
X585334Y587000*
X595234Y626700*
X606834Y624300*
X580538Y1394000*
X562334Y1428300*
X573034Y1466400*
Y1462400*
X572734Y1453300*
X589834Y1458000*
G54D44*
G55*
X509843Y161889D03*
Y171889*
Y181889*
Y191889*
Y204409*
Y214409*
Y224409*
Y234409*
Y244409*
Y256929*
Y266929*
Y276929*
Y286929*
X539843Y161889*
Y171889*
X529843Y161889*
Y171889*
X519843Y161889*
Y171889*
X539843Y181889*
Y191889*
X529843Y181889*
Y191889*
X519843Y181889*
Y191889*
X539843Y204409*
Y214409*
Y224409*
Y234409*
Y244409*
X529843Y204409*
Y214409*
Y224409*
Y234409*
Y244409*
X519843Y204409*
Y214409*
Y224409*
Y234409*
Y244409*
X539843Y256929*
Y266929*
X529843Y256929*
Y266929*
X519843Y256929*
Y266929*
X539843Y276929*
Y286929*
X529843Y276929*
Y286929*
X519843Y276929*
Y286929*
X608740Y161889*
Y171889*
X598740Y161889*
Y171889*
X588740Y161889*
Y171889*
X578740Y161889*
Y171889*
X608740Y181889*
Y191889*
X598740Y181889*
Y191889*
X588740Y181889*
Y191889*
X578740Y181889*
Y191889*
X608740Y204409*
Y214409*
Y224409*
Y234409*
Y244409*
X598740Y204409*
Y214409*
Y224409*
Y234409*
Y244409*
X588740Y204409*
Y214409*
Y224409*
Y234409*
Y244409*
X578740Y204409*
Y214409*
Y224409*
Y234409*
Y244409*
X608740Y256929*
Y266929*
X598740Y256929*
Y266929*
X588740Y256929*
Y266929*
X578740Y256929*
Y266929*
X608740Y276929*
Y286929*
X598740Y276929*
Y286929*
X588740Y276929*
Y286929*
X578740Y276929*
Y286929*
G54D63*
G55*
X500384Y1613297D03*
Y1619703*
X530884Y1613297*
Y1619703*
X559384Y1613297*
Y1619703*
X586884Y1613297*
Y1619703*
G54D33*
G55*
X563843Y710500D03*
X546425*
G54D31*
G55*
X453502Y1093083D03*
X461002Y1089208*
Y1096958*
X541152Y566991*
Y574741*
X533652Y570866*
X541152Y1255968*
Y1263718*
X533652Y1259843*
G54D45*
G55*
X476632Y238899D03*
X481334Y238900*
X491834Y254200*
X474234Y577300*
X510634Y727600*
X492336Y1128347*
X533034Y476600*
X525434Y557700*
X558199Y673094*
X552599*
X554034Y722600*
X523634Y976700*
X559934Y975800*
X575834Y476700*
X592434Y696500*
X573434Y1111300*
X578136Y1111347*
X562634Y1471200*
G54D36*
G55*
X510434Y71500D03*
X492934Y662300*
Y657600*
X483434Y1764700*
X462734Y1769900*
X544934Y769100*
Y764100*
X534434Y1058400*
Y1053700*
X576581Y1878698*
X576534Y1883700*
X617034Y1652700*
Y1648000*
G54D81*
G55*
X609599Y631371D03*
Y634971*
G54D54*
G55*
X502537Y633502D03*
Y606702*
X551231Y1125298*
Y1152098*
X527631Y1883198*
Y1909998*
G54D16*
G55*
X447734Y249100D03*
X457034Y269471*
X449144Y302982*
X440134Y578000*
X456434Y593000*
X456234Y578100*
X453634Y1102000*
X449190Y1774189*
X473034Y137200*
X465334Y318700*
X492334Y385100*
X491534Y430600*
X492034Y412900*
X490834Y421900*
X500034Y427200*
X495134Y510500*
X506534Y536300*
X499534Y565500*
X478799Y642933*
X472471Y650145*
X466134Y605000*
X486334Y667884*
X494134Y775000*
Y766000*
X472234Y866100*
X505634Y900500*
X495034Y900000*
X493234Y904800*
X502134Y966000*
X496034Y969100*
X489134Y966800*
X510634Y985900*
X480634Y974100*
X466334Y1091700*
X481234Y1132700*
X500134Y1232600*
X462134Y1575000*
X482434Y1609200*
X493534Y1605900*
X491434Y1641300*
X488634Y1627500*
X462034Y1656300*
X490634Y1716500*
X501634Y1717000*
Y1699000*
X462134Y1718500*
X462083Y1709451*
X508134Y1766500*
X500634Y1760000*
X501634Y1733000*
X510134Y1802000*
X502134Y1813000*
X501134Y1798000*
X486134Y1805500*
X504634Y1838500*
X502134Y1847000*
X501634Y1830000*
X495134Y1917000*
X547634Y442000*
X551634Y429000*
X554234Y408900*
X544134Y486100*
X535634Y469500*
X544634Y476700*
X526034Y541600*
X528934Y545600*
X549934Y598700*
X541152Y584900*
X535472Y580496*
X547699Y592846*
X512753Y581742*
X512034Y574500*
X530934Y557400*
X525634Y567600*
X528712Y605771*
X522197Y629134*
X523679Y601197*
X520597Y623143*
X551222Y665912*
X548434Y656600*
X540534Y658500*
X515194Y695200*
X515134Y689900*
X554336Y657500*
X558134Y653600*
X524634Y728000*
X534634Y732000*
X546634Y724500*
X538134Y809500*
X548434Y837000*
X521534Y848900*
X532534Y838300*
X527834Y877100*
X521934Y865300*
X540234Y876700*
X521834Y858100*
X537334Y953500*
X542118Y946835*
X549188Y945600*
X560037Y958178*
X523634Y950500*
X539534Y997850*
X548214Y992900*
X556834Y998400*
X516734Y965900*
X519676Y987958*
X527092Y966958*
X532634Y966500*
X560034Y1003400*
X520634Y1030500*
X514634Y1009500*
X557634Y1076800*
X551996Y1385500*
X558134Y1416425*
X528634Y1407500*
X529134Y1443000*
X530134Y1460750*
X542158Y1452079*
X546256Y1448001*
X546329Y1456070*
X550472Y1452021*
X546158Y1452000*
X529334Y1433800*
X528834Y1450700*
X532134Y1429500*
X552134Y1431300*
X556109Y1435400*
X556434Y1468800*
X540967Y1469667*
X546634Y1519500*
X533467Y1498167*
X559314Y1486680*
X527134Y1564700*
X518634Y1610000*
X549634Y1606000*
X527634Y1717000*
Y1696500*
X528134Y1707000*
X538634Y1719500*
X539134Y1709500*
X538634Y1699000*
X548634Y1710110*
Y1696610*
X515634Y1713610*
Y1700110*
X548634Y1725110*
X540634Y1768500*
X537634Y1727000*
X546634Y1732000*
X548634Y1760000*
X526634Y1775500*
X515634Y1726000*
X516134Y1774110*
X548634Y1747110*
X539634Y1801000*
X517634Y1785000*
X526634Y1796000*
X527134Y1786000*
X515634Y1793110*
X537402Y1777300*
X536902Y1789110*
X549134Y1811500*
X548634Y1796500*
X513134Y1869600*
X543134Y1843500*
X526134Y1850500*
X549634Y1836500*
Y1850500*
X537634Y1851610*
X514234Y1844500*
X514834Y1852300*
X511134Y1915000*
X591746Y438169*
X572534Y408200*
X573534Y470800*
X578134Y522500*
X603934Y532200*
X580634Y533000*
X593334Y541900*
X578634Y574600*
X574364Y571700*
X564334Y566400*
X605434Y608635*
X586334Y620800*
X575797Y634051*
X577729Y618300*
X580469Y640400*
X574334Y644600*
X592234Y604717*
X608151Y620013*
X603234Y652900*
X582334Y653200*
X602134Y691000*
X571134Y701000*
X587634Y695000*
X574634Y675000*
X574134Y711750*
X596734Y703300*
X589634Y916500*
X562634Y953000*
X568634Y951500*
X572234Y1007100*
X591134Y1027000*
X607634Y1268500*
X588908Y1414374*
X565234Y1463900*
X563534Y1454300*
X562134Y1447600*
X594634Y1450600*
X567134Y1448500*
X571534Y1499900*
X565634Y1481425*
X577634Y1479500*
X565634Y1651000*
X568134Y1696500*
Y1712500*
X610634Y1716500*
X587634*
X596634Y1716000*
X611134Y1704000*
X597634Y1705000*
X587634*
X592134Y1697000*
X603402Y1697110*
X581134*
Y1710610*
Y1725610*
X567634Y1727500*
X611134Y1726000*
X612734Y1765100*
X591634Y1773000*
X581634Y1771110*
X602402Y1776000*
X568134Y1800500*
X567134Y1824000*
X598134Y1781500*
X585634Y1782000*
X584634Y1798500*
X595634Y1798000*
X608134Y1798500*
X591134Y1790000*
X601902Y1790110*
X581134*
X566134Y1877500*
X568134Y1851000*
X567634Y1839500*
X590634Y1852500*
X612234Y1838300*
X602134Y1852610*
X580634Y1851110*
X568995Y1889461*
X619062Y435800*
X626634Y481500*
X615134Y1133000*
X618134Y1432000*
X613634Y1696500*
X614134Y1738500*
X614634Y1804500*
X615134Y1790000*
X614134Y1852500*
G54D92*
G55*
X525591Y1773425D03*
G54D89*
G55*
X448417Y307282D03*
X455034Y1721700*
X486534Y207900*
X486034Y236600*
X485734Y191600*
X461834Y253500*
X492134Y264300*
X468334Y343800*
X510534Y530500*
X507534Y587600*
X478734Y573500*
X490534Y673400*
X486534*
X493234Y909400*
X506136Y1134497*
X462034Y1660800*
X525234Y530500*
X554034Y585204*
X549934*
X522199Y594071*
X526399*
X521599Y606971*
X524334Y662300*
X540034Y881400*
X531734*
X548434*
X551663Y952344*
X546663*
X541663*
X529634Y1420300*
X520634*
X512634Y1461800*
X534134Y1420300*
X536634Y1486800*
X599734Y529100*
X584734Y529000*
X587134Y575200*
X599334Y623700*
X609499Y642371*
X566899Y658671*
X583634Y683800*
X578634Y708300*
X577034Y999700*
X581234Y999800*
X592634Y994300*
X588634*
X572934Y999800*
X564134Y1408404*
X563834Y1400604*
X566634Y1440300*
G54D88*
G55*
X451134Y1644300D03*
X450934Y1720700*
X452734Y1692800*
X489434Y155300*
Y163300*
Y179300*
Y159300*
Y175300*
X479034Y213400*
X490334Y217000*
X489434Y199300*
X465334Y272300*
X461634Y321300*
X503334Y431300*
X493534Y577200*
X477934Y916400*
X501234Y999800*
X462634Y1083600*
X481934Y1769800*
X520837Y61502*
X518334Y71500*
X550434Y437500*
X511090Y690465*
X513234Y686400*
X558490Y692165*
X558390Y688065*
Y683665*
X545434Y670600*
X516530Y848500*
Y844100*
Y852900*
X516534Y865700*
Y857200*
Y861500*
X544434Y1408200*
X523834Y1451000*
X542234Y1425900*
X523834Y1439000*
X516834Y1484000*
X561334Y1482000*
X592434Y545600*
X595234Y622700*
X584863Y615065*
X604334Y701100*
X584630Y1415000*
X573034Y1458400*
X584634Y1423400*
X584630Y1419200*
X623334Y439500*
G54D55*
G55*
X496009Y674606D03*
X498569*
X501129*
Y681106*
X496009*
G54D82*
G55*
X570234Y1401696D03*
Y1410096*
X587734Y1446404*
Y1438004*
G54D73*
G55*
X545309Y846304D03*
X542754*
X540194*
X537634*
X535074*
X532514*
X529959*
Y868504*
X532514*
X535074*
X537634*
X540194*
X542754*
X545309*
X543094Y985200*
X545654*
X548214*
X550774*
Y963000*
X548214*
X545654*
X543094*
X584959Y732304*
X587514*
X590074*
X592634*
X595194*
X597754*
X600309*
Y710104*
X597754*
X595194*
X592634*
X590074*
X587514*
X584959*
X566474Y959500*
X569034*
X571594*
X574154*
X576714*
X579274*
X581834*
X584394*
Y981700*
X581834*
X579274*
X576714*
X574154*
X571594*
X569034*
X566474*
G54D46*
G55*
X476632Y244499D03*
X481334Y244500*
X491834Y259800*
X474234Y582900*
X510634Y733200*
X492336Y1133947*
X533034Y482200*
X525434Y563300*
X558199Y678694*
X552599*
X554034Y728200*
X523634Y982300*
X559934Y981400*
X575834Y482300*
X592434Y702100*
X573434Y1116900*
X578136Y1116947*
X562634Y1476800*
G54D37*
G55*
X497132Y56503D03*
X496532Y71003*
X490134Y240000*
X490734Y211300*
X489734Y195000*
X483434Y263300*
X487434*
X466334Y256900*
X491734Y249200*
X502834Y543300*
X507734Y574500*
X503034Y558800*
X468134Y581300*
X506334Y705900*
X506134Y730800*
X472534Y896100*
X510532Y1126103*
X492632Y1123803*
X492332Y1142003*
X477434Y1755700*
X545934Y588596*
X558034*
X520434Y573200*
X558469Y662029*
X534034Y662200*
X544734Y660200*
X545434Y670600*
X548734Y831800*
X540334*
X532034Y831796*
X550805Y939756*
X546434Y939700*
X539634*
X560634Y947800*
X552434Y1001300*
X548434*
X543934*
X528134Y979700*
X552134Y1424200*
X556634*
X524634Y1464200*
X547134Y1424200*
X524734Y1423700*
X558134Y1501700*
X554134*
X550134*
X546134*
X542134*
X538134*
X522634Y1479200*
X565913Y543071*
X574434Y582200*
X582634Y570000*
X565813Y557171*
X580469Y635829*
X577569Y653329*
X562669Y662029*
X573369Y653329*
X596834Y699600*
X583634Y702700*
X587634*
X578134Y949200*
X582134*
X586134*
X574134*
X569634Y947800*
X565134*
X568234Y1003100*
X564134Y1003200*
X585765Y1431081*
X589965Y1430281*
X581465Y1431081*
X594534Y1430200*
X580134Y1491200*
X575634*
X571134*
X566134Y1501700*
X562134*
X567034Y1491100*
X577634Y1474100*
G54D83*
G55*
X576634Y1437250D03*
X572759Y1444750*
X580509*
G54D56*
G55*
X480884Y690560D03*
Y688000*
Y685440*
X487384*
Y690560*
X465384*
Y688000*
Y685440*
X471884*
Y690560*
G54D74*
G55*
X542934Y1397140D03*
Y1399700*
Y1402260*
X535534*
Y1399700*
Y1397140*
G54D65*
G55*
X477334Y1760300D03*
X515934Y537800*
X525234*
X527734Y553300*
X536734Y593700*
X542034Y603500*
X599734Y536400*
X590034Y536500*
G54D38*
G55*
X497132Y53103D03*
X496532Y67603*
X490134Y236600*
X490734Y207900*
X489734Y191600*
X483434Y259900*
X487434*
X466334Y253500*
X491734Y245800*
X502834Y539900*
X507734Y571100*
X503034Y555400*
X468134Y577900*
X506334Y702500*
X506134Y727400*
X472534Y892700*
X510532Y1122703*
X492632Y1120403*
X492332Y1138603*
X477434Y1752300*
X545934Y585196*
X558034*
X520434Y569800*
X558469Y658629*
X534034Y658800*
X544734Y656800*
X545434Y667200*
X548734Y828400*
X540334*
X532034Y828396*
X550805Y936356*
X546434Y936300*
X539634*
X560634Y944400*
X552434Y997900*
X548434*
X543934*
X528134Y976300*
X552134Y1420800*
X556634*
X524634Y1460800*
X547134Y1420800*
X524734Y1420300*
X558134Y1498300*
X554134*
X550134*
X546134*
X542134*
X538134*
X522634Y1475800*
X565913Y539671*
X574434Y578800*
X582634Y566600*
X565813Y553771*
X580469Y632429*
X577569Y649929*
X573369*
X562669Y658629*
X583634Y699300*
X596834Y696200*
X587634Y699300*
X578134Y945800*
X582134*
X586134*
X574134*
X569634Y944400*
X565134*
X568234Y999700*
X564134Y999800*
X585765Y1427681*
X589965Y1426881*
X581465Y1427681*
X594534Y1426800*
X580134Y1487800*
X575634*
X571134*
X566134Y1498300*
X562134*
X567034Y1487700*
X577634Y1470700*
G54D29*
G55*
X461493Y1680500D03*
X489775*
G54D47*
G55*
X485334Y252800D03*
X469134Y294300*
X502634Y591000*
X505734Y986600*
X496734Y1025000*
X512981Y61398*
X546034Y380100*
X520663Y533679*
X536234Y986000*
Y990800*
X523934Y1455500*
X535934Y1474500*
X595034Y532100*
X594834Y553300*
X611155Y613535*
X589434Y1462500*
G54D57*
G55*
X479034Y883800D03*
Y894800*
X492934Y986600*
Y975600*
X468134Y1022500*
Y1033500*
X525134Y931000*
Y942000*
X576134Y732000*
Y721000*
G54D84*
G55*
X571434Y1471800D03*
Y1480800*
G54D39*
G55*
X500936Y56547D03*
X500534Y71754*
X504334Y741500*
X504834Y719100*
X482934Y1013100*
X532634Y597500*
X575499Y611321*
G54D66*
G55*
X480934Y1760300D03*
X519534Y537800*
X528834*
X531334Y553300*
X540334Y593700*
X545634Y603500*
X603334Y536400*
X593634Y536500*
G54D75*
G55*
X554134Y1409454D03*
X550259Y1401954*
X558009*
G54D48*
G55*
X498769Y361900D03*
X539869Y361800*
X528499Y361900*
X569599Y361800*
X586969Y1507700*
X616699*
G54D64*
G55*
X493035Y949600D03*
X515833*
G54D67*
G55*
X525591Y1747835D03*
Y1823031*
X608071Y1328740*
X590551Y1747835*
Y1823031*
G54D76*
G55*
X541016Y1461600D03*
X543575*
X546134*
X548693*
X551252*
Y1442400*
X548693*
X546134*
X543575*
X541016*
G54D49*
G55*
X498134Y440000D03*
X503134*
X508134*
X489534Y1575600*
X494534*
X499534*
X504534*
X525634Y439500*
X530634*
X535634*
X540634*
X513134Y440000*
X557634Y1575500*
X522634*
X527634*
X532634*
X537634*
X570134Y439500*
X575134*
X580134*
X585134*
X598134*
X603134*
X608134*
X613134*
X591634Y1575500*
X596634*
X601634*
X606634*
X562634*
X567634*
X572634*
G54D85*
G55*
X590551Y1773425D03*
G54D77*
G55*
X555734Y1457118D03*
Y1454559*
Y1452000*
Y1449441*
Y1446882*
X536534*
Y1449441*
Y1452000*
Y1454559*
Y1457118*
G54D68*
G55*
X518469Y544750D03*
X516504*
X514534*
X512564*
X510599*
Y561050*
X512564*
X514534*
X516504*
X518469*
X537844Y612629*
X539809*
X541779*
X543749*
X545714*
X547684*
X549654*
X551624*
X553589*
X555559*
X557529*
X559494*
Y646029*
X557529*
X555559*
X553589*
X551624*
X549654*
X547684*
X545714*
X543749*
X541779*
X539809*
X537844*
X582269Y542950*
X580304*
X578334*
X576364*
X574399*
Y559250*
X576364*
X578334*
X580304*
X582269*
G54D59*
G55*
X506534Y980050D03*
Y976300*
Y972550*
X517134*
Y976300*
Y980050*
G54D78*
G55*
X546134Y1452000D03*
G54D69*
G55*
X531969Y640154D03*
Y638189*
Y636219*
Y634249*
Y632284*
Y630314*
Y628344*
Y626374*
Y624409*
Y622439*
Y620469*
Y618504*
X565369*
Y620469*
Y622439*
Y624409*
Y626374*
Y628344*
Y630314*
Y632284*
Y634249*
Y636219*
Y638189*
Y640154*
G54D79*
G55*
X579134Y64500D03*
X581634Y1906000*
G54D198*
G55*
X-27157Y1657822D03*
X-33774Y243404*
X-65274Y1757204*
X-64774Y1728504*
X-64474Y1773504*
X-40574Y1711604*
X-70874Y1700804*
X-47074Y1621304*
X-89274Y1434604*
X-86274Y1377504*
X-57474Y1391604*
X-69274Y1291704*
X-65274*
X-71974Y1055704*
X-84876Y830607*
X-40774Y304304*
X-103974Y1434604*
X-132774Y1379900*
X-128674*
X-100939Y1371033*
X-105139*
X-100339Y1358133*
X-103074Y1302804*
X-118774Y1083704*
X-110474*
X-127174*
X-130403Y1012760*
X-125403*
X-120403*
X-108374Y544804*
X-99374*
X-91374Y503304*
X-112874Y544804*
X-115374Y478304*
X-178474Y1436004*
X-163474Y1436104*
X-165874Y1389904*
X-178074Y1341404*
X-188239Y1322733*
X-145639Y1306433*
X-162374Y1281304*
X-157374Y1256804*
X-155774Y965404*
X-159974Y965304*
X-171374Y970804*
X-167374*
X-151674Y965304*
X-142874Y556700*
X-142574Y564500*
X-145374Y524804*
G54D199*
G55*
X-36974Y1647204D03*
X-37974Y884904*
X-26474Y324204*
X-26274Y247804*
X-28074Y275704*
X-64774Y1813204*
Y1805204*
Y1789204*
Y1809204*
Y1793204*
X-54374Y1755104*
X-65674Y1751504*
X-64774Y1769204*
X-40674Y1696204*
X-78674Y1537204*
X-68874Y1391304*
X-86430Y1278039*
X-88574Y1282104*
X-53274Y1052104*
X-76574Y968704*
X-57274Y198704*
X-96177Y1907002*
X-93674Y1897004*
X-125774Y1531004*
X-133830Y1276339*
X-133730Y1280439*
Y1284839*
X-120774Y1297904*
X-91870Y1120004*
Y1124404*
Y1115604*
X-91874Y1102804*
Y1111304*
Y1107004*
X-119774Y560304*
X-99174Y517504*
X-117574Y542604*
X-99174Y529504*
X-92174Y484504*
X-136674Y486504*
X-167774Y1422904*
X-170574Y1345804*
X-160203Y1353439*
X-179674Y1267404*
X-159970Y553504*
X-148374Y510104*
X-159974Y545104*
X-159970Y549304*
X-198674Y1529004*
G54D12*
G55*
X-37795Y1943701D03*
Y1857087*
Y1510473*
Y1423858*
Y1250630*
Y1164016*
X-37874Y804504*
X-37795Y717874*
Y544646*
Y458032*
Y111418*
Y24803*
G54D200*
G55*
X-35874Y198604D03*
X-83574Y1897004*
X-66074Y1306204*
Y1310904*
X-56574Y203804*
X-118074Y1199404*
Y1204404*
X-107574Y910104*
Y914804*
X-190174Y315804*
Y320504*
X-149721Y89806*
X-149674Y84804*
G54D201*
G55*
X-30774Y1570704D03*
Y1550204*
X-26974Y1301504*
X-88974Y1570004*
X-55574Y1570704*
X-88974Y1549504*
X-55574Y1550204*
X-51774Y1301504*
X-81474Y1170104*
X-71574Y877904*
X-44474Y417004*
X-69274*
X-120974Y1880004*
X-113774Y1570004*
Y1549504*
X-106274Y1170104*
X-96374Y877904*
X-145774Y1880004*
X-193174Y1570604*
X-168374*
X-193074Y1611804*
X-168274*
X-193274Y1591604*
X-168474*
X-193174Y1550104*
X-168374*
X-192774Y437004*
X-167974*
X-192874Y416904*
X-168074*
G54D202*
G55*
X-29224Y187504D03*
X-85827Y1914002*
X-79524Y1384504*
X-66224*
X-52924Y1375504*
X-66224*
X-89724Y1253104*
X-89224Y1228104*
X-68024Y956704*
X-81324*
X-72324Y936404*
X-85624*
X-42524Y187504*
X-99127Y1914002*
X-103724Y1900004*
X-117024*
X-103024Y1253104*
X-102524Y1228104*
G54D203*
G55*
X-79676Y1915557D03*
X-79274Y1900350*
X-83074Y1230604*
X-83574Y1253004*
X-61674Y959004*
X-111374Y1374604*
X-154239Y1360783*
G54D13*
G55*
X-23780Y1920394D03*
Y1910394*
Y1900394*
Y1890394*
Y1880394*
Y1487165*
Y1477165*
Y1467165*
Y1457165*
Y1447165*
Y1227323*
Y1217323*
Y1207323*
Y1197323*
Y1187323*
Y781181*
Y771181*
Y761181*
Y751181*
Y741181*
Y521339*
Y511339*
Y501339*
Y491339*
Y481339*
Y88110*
Y78110*
Y68110*
Y58110*
Y48110*
X-136811Y189685*
X-126811*
X-172874Y578004*
Y588004*
Y598004*
X-146811Y189685*
G54D204*
G55*
X-38174Y180704D03*
X-72374Y1395504*
X-79074Y824004*
X-89774Y1002304*
X-94874Y825504*
X-102674Y537004*
Y533604*
Y525704*
X-171274Y1419204*
X-152174Y1273004*
X-141174Y536504*
G54D14*
G55*
X-35433Y1811024D03*
Y1338583*
X-25590Y629921*
X-35433Y157481*
X-187008Y1889764*
X-187007Y1397638*
X-187008Y807087*
Y78740*
G54D17*
G55*
X-55118Y1900394D03*
Y1467166*
Y1207323*
Y761181*
Y501339*
Y68111*
G54D205*
G55*
X-79874Y1494956D03*
Y1477052*
X-97874Y1494956*
Y1477052*
X-183874Y1495456*
Y1477552*
X-165874Y1495456*
Y1477552*
G54D206*
G55*
X-37874Y1397704D03*
X-32174Y862504*
X-26474Y328304*
X-27774Y198904*
X-75174Y1905004*
X-64774Y1797204*
Y1785204*
Y1801204*
Y1781204*
X-65674Y1747504*
X-54374Y1751104*
X-40556Y1704287*
X-64774Y1688504*
X-86418Y1273869*
X-87874Y1286304*
X-73174Y1238504*
X-76574Y964204*
X-67474Y947904*
X-80174Y943104*
X-80274Y947604*
X-45874Y872504*
X-76674Y793404*
X-38574Y194104*
X-42874Y180304*
X-106574Y1418904*
X-91574Y1398604*
X-99174Y1297504*
X-123474Y1308304*
X-112774Y1306304*
X-95674Y1260604*
X-94174Y1235104*
X-111974Y560404*
X-137674Y540204*
X-99174Y522004*
X-117574Y546904*
X-157974Y1537704*
X-153174Y1400504*
X-160674Y1381504*
X-170574Y1341804*
X-182174Y1344204*
X-155878Y574504*
X-148374Y502104*
Y506104*
X-148074Y515204*
X-165174Y510504*
G54D207*
G55*
X-31974Y1277604D03*
X-36774*
X-81974Y1392304*
X-73509Y1274598*
X-78409*
X-89874Y1260304*
X-80074Y1257504*
X-75074*
X-78674Y987104*
X-72074Y964404*
X-89272Y830751*
X-100174Y1090050*
X-95374*
X-101874Y1005704*
X-111374Y988704*
X-137774Y976004*
X-148274Y1396104*
X-166409Y1358825*
G54D208*
G55*
X-34574Y180704D03*
X-68774Y1395504*
X-86174Y1002304*
X-75474Y824004*
X-91274Y825504*
X-99074Y537004*
Y533604*
X-137574Y536504*
X-99074Y525704*
X-167674Y1419204*
X-148574Y1273004*
G54D209*
G55*
X-78076Y830157D03*
Y843457*
X-49474Y200954*
Y214254*
X-96376Y832257*
Y845557*
G54D18*
G55*
X-88583Y1849095D03*
Y1639095*
X-157480Y1849095*
Y1639095*
G54D15*
G55*
X-39173Y1737638D03*
Y1747638*
Y1757638*
Y1629941*
Y1609941*
Y1619941*
Y1064587*
Y1044587*
Y1054587*
Y913917*
Y923917*
Y903917*
Y348563*
Y358563*
Y338563*
Y210866*
Y220866*
Y230866*
G54D71*
G55*
X-81774Y1418404D03*
X-140609Y1375075*
X-133709Y1374875*
X-100845Y1351169*
X-139809Y1366575*
X-112874Y1365304*
X-109774Y1314404*
X-124974Y538404*
X-144645Y1419983*
X-152203Y1369739*
X-148009Y1375275*
X-168574Y1352604*
X-158903Y1340939*
X-147803Y1364339*
X-164574Y1341704*
X-186874Y1262004*
X-155474Y973904*
X-161874Y974004*
X-149874*
G54D210*
G55*
X-42874Y1387204D03*
X-65974Y937704*
X-95274Y1394404*
X-157374Y1389904*
X-172474Y1360004*
X-158374Y1269304*
G54D211*
G55*
X-97309Y1325875D03*
Y1333475*
X-97374Y506804*
Y499204*
X-179974Y1419404*
Y1427004*
X-177974Y1360904*
Y1353304*
X-160139Y1359533*
Y1367133*
X-174874Y510804*
Y503204*
G54D212*
G55*
X-88074Y491004D03*
X-115474Y1410204*
X-123074*
X-95674Y491004*
X-114644Y487864*
X-107044*
X-191574Y362004*
X-188574Y327504*
X-199174Y362004*
X-196174Y327504*
G54D213*
G55*
X-35345Y1705951D03*
X-27595*
X-31470Y1713451*
X-32799Y1663154*
X-36674Y1655654*
X-35499Y319454*
X-35166Y253636*
X-27416*
X-31291Y261136*
X-40549Y1663154*
X-62691Y1066136*
X-66566Y1058636*
X-58816*
X-86626Y355207*
Y348801*
X-43249Y319454*
X-39374Y326954*
X-139399Y1245954*
X-117126Y355207*
Y348801*
X-149499Y1286254*
X-157249*
X-153374Y1278754*
X-147149Y1245954*
X-143274Y1238454*
X-155899Y567050*
X-163649*
X-159774Y559550*
X-173368Y531035*
X-181118*
X-177243Y523535*
X-146568Y546235*
X-154318*
X-150443Y538735*
X-145626Y355207*
Y348801*
X-173126Y355207*
Y348801*
G54D19*
G55*
X-88583Y1829095D03*
Y1659095*
X-157480Y1829095*
Y1659095*
G54D214*
G55*
X-80074Y1882304D03*
X-80476Y1210607*
X-71574Y918404*
X-106874Y1882304*
X-107276Y1210607*
X-98374Y918404*
G54D215*
G55*
X-31974Y1283204D03*
X-36774*
X-81974Y1397904*
X-89874Y1265904*
X-73509Y1280198*
X-78409*
X-80074Y1263104*
X-75074*
X-78674Y992704*
X-72074Y970004*
X-89272Y836351*
X-100174Y1095650*
X-95374*
X-101874Y1011304*
X-111374Y994304*
X-137774Y981604*
X-148274Y1401704*
X-166409Y1364425*
G54D216*
G55*
X-86121Y1907106D03*
X-58474Y1715704*
X-42274Y1674204*
X-75774Y1377504*
X-78874Y981904*
X-69874Y943504*
X-119174Y1588404*
X-93803Y1434825*
X-109374Y982504*
Y977704*
X-97074Y513004*
X-109074Y494004*
X-168174Y1436404*
X-167974Y1415204*
X-184295Y1354969*
X-162574Y506004*
G54D217*
G55*
X-42874Y1383604D03*
X-65974Y934104*
X-95274Y1390804*
X-157374Y1386304*
X-172474Y1356404*
X-158374Y1265704*
G54D218*
G55*
X-86774Y469804D03*
Y445004*
X-132172Y60201*
Y85001*
X-153672Y817201*
Y842001*
G54D219*
G55*
X-101080Y1291089D03*
Y1286089*
Y1281089*
Y1276089*
X-121180*
Y1281089*
Y1286089*
Y1291089*
G54D220*
G55*
X-179244Y1333685D03*
X-167674*
X-179244Y1322665*
X-167674*
G54D221*
G55*
X-35774Y1721604D03*
X-33174Y1640004*
X-24074Y311404*
X-35074*
X-23674Y269304*
X-34674*
X-46774Y1721604*
X-44174Y1640004*
X-132570Y576204*
X-113874Y581004*
X-124874*
X-143570Y576204*
X-161874Y581004*
X-150874*
G54D222*
G55*
X-35574Y862504D03*
X-29874Y328304*
X-31174Y198904*
X-78574Y1905004*
X-68174Y1797204*
Y1785204*
Y1801204*
Y1781204*
X-69074Y1747504*
X-57774Y1751104*
X-43956Y1704287*
X-68174Y1688504*
X-41274Y1397704*
X-76574Y1238504*
X-79974Y964204*
X-70874Y947904*
X-83574Y943104*
X-83674Y947604*
X-49274Y872504*
X-80074Y793404*
X-41974Y194104*
X-46274Y180304*
X-109974Y1418904*
X-94974Y1398604*
X-89818Y1273869*
X-102574Y1297504*
X-126874Y1308304*
X-116174Y1306304*
X-91274Y1286304*
X-99074Y1260604*
X-97574Y1235104*
X-115374Y560404*
X-102574Y522004*
X-120974Y546904*
X-161374Y1537704*
X-156574Y1400504*
X-164074Y1381504*
X-173974Y1341804*
X-185574Y1344204*
X-159278Y574504*
X-141074Y540204*
X-151774Y502104*
Y506104*
X-151474Y515204*
X-168574Y510504*
G54D20*
G55*
X-88583Y1806615D03*
Y1796615*
Y1786615*
Y1776615*
Y1764095*
Y1754095*
Y1744095*
Y1734095*
Y1724095*
Y1711575*
Y1701575*
Y1691575*
Y1681575*
X-118583Y1806615*
Y1796615*
X-108583Y1806615*
Y1796615*
X-98583Y1806615*
Y1796615*
X-118583Y1786615*
Y1776615*
X-108583Y1786615*
Y1776615*
X-98583Y1786615*
Y1776615*
X-118583Y1764095*
Y1754095*
Y1744095*
Y1734095*
Y1724095*
X-108583Y1764095*
Y1754095*
Y1744095*
Y1734095*
Y1724095*
X-98583Y1764095*
Y1754095*
Y1744095*
Y1734095*
Y1724095*
X-118583Y1711575*
Y1701575*
X-108583Y1711575*
Y1701575*
X-98583Y1711575*
Y1701575*
X-118583Y1691575*
Y1681575*
X-108583Y1691575*
Y1681575*
X-98583Y1691575*
Y1681575*
X-187480Y1806615*
Y1796615*
X-177480Y1806615*
Y1796615*
X-167480Y1806615*
Y1796615*
X-157480Y1806615*
Y1796615*
X-187480Y1786615*
Y1776615*
X-177480Y1786615*
Y1776615*
X-167480Y1786615*
Y1776615*
X-157480Y1786615*
Y1776615*
X-187480Y1764095*
Y1754095*
Y1744095*
Y1734095*
Y1724095*
X-177480Y1764095*
Y1754095*
Y1744095*
Y1734095*
Y1724095*
X-167480Y1764095*
Y1754095*
Y1744095*
Y1734095*
Y1724095*
X-157480Y1764095*
Y1754095*
Y1744095*
Y1734095*
Y1724095*
X-187480Y1711575*
Y1701575*
X-177480Y1711575*
Y1701575*
X-167480Y1711575*
Y1701575*
X-157480Y1711575*
Y1701575*
X-187480Y1691575*
Y1681575*
X-177480Y1691575*
Y1681575*
X-167480Y1691575*
Y1681575*
X-157480Y1691575*
Y1681575*
G54D223*
G55*
X-79124Y355207D03*
Y348801*
X-109624Y355207*
Y348801*
X-138124Y355207*
Y348801*
X-165624Y355207*
Y348801*
G54D224*
G55*
X-142583Y1258004D03*
X-125165*
G54D225*
G55*
X-32242Y875421D03*
X-39742Y879296*
Y871546*
X-119892Y1401513*
Y1393763*
X-112392Y1397638*
X-119892Y712536*
Y704786*
X-112392Y708661*
G54D226*
G55*
X-55372Y1729605D03*
X-60074Y1729604*
X-70574Y1714304*
X-52974Y1391204*
X-89374Y1240904*
X-71076Y840157*
X-111774Y1491904*
X-104174Y1410804*
X-136939Y1295410*
X-131339*
X-132774Y1245904*
X-102374Y991804*
X-138674Y992704*
X-154574Y1491804*
X-171174Y1272004*
X-152174Y857204*
X-156876Y857157*
X-141374Y497304*
G54D227*
G55*
X-89174Y1897004D03*
X-71674Y1306204*
Y1310904*
X-62174Y203804*
X-41474Y198604*
X-123674Y1199404*
Y1204404*
X-113174Y910104*
Y914804*
X-155321Y89806*
X-155274Y84804*
X-195774Y315804*
Y320504*
G54D228*
G55*
X-188339Y1337133D03*
Y1333533*
G54D229*
G55*
X-81277Y1335002D03*
Y1361802*
X-129971Y843206*
Y816406*
X-106371Y85306*
Y58506*
G54D16*
G55*
X-26474Y1719404D03*
X-35774Y1699033*
X-27884Y1665522*
X-18874Y1390504*
X-35174Y1375504*
X-34974Y1390404*
X-32374Y866504*
X-27930Y194315*
X-51774Y1831304*
X-44074Y1649804*
X-71074Y1583404*
X-70274Y1537904*
X-70774Y1555604*
X-69574Y1546604*
X-78774Y1541304*
X-73874Y1458004*
X-85274Y1432204*
X-78274Y1403004*
X-57539Y1325571*
X-51211Y1318359*
X-44874Y1363504*
X-65074Y1300620*
X-72874Y1193504*
Y1202504*
X-50974Y1102404*
X-84374Y1068004*
X-73774Y1068504*
X-71974Y1063704*
X-80874Y1002504*
X-74774Y999404*
X-67874Y1001704*
X-89374Y982604*
X-59374Y994404*
X-45074Y876804*
X-59974Y835804*
X-78874Y735904*
X-40874Y393504*
X-61174Y359304*
X-72274Y362604*
X-70174Y327204*
X-67374Y341004*
X-40774Y312204*
X-69374Y252004*
X-80374Y251504*
Y269504*
X-40874Y250004*
X-40823Y259053*
X-86874Y202004*
X-79374Y208504*
X-80374Y235504*
X-88874Y166504*
X-80874Y155504*
X-79874Y170504*
X-64874Y163004*
X-83374Y130004*
X-80874Y121504*
X-80374Y138504*
X-73874Y51504*
X-126374Y1526504*
X-130374Y1539504*
X-132974Y1559604*
X-122874Y1482404*
X-114374Y1499004*
X-123374Y1491804*
X-104774Y1426904*
X-107674Y1422904*
X-128674Y1369804*
X-119892Y1383604*
X-114212Y1388008*
X-126439Y1375658*
X-91493Y1386762*
X-90774Y1394004*
X-109674Y1411104*
X-104374Y1400904*
X-107452Y1362733*
X-100937Y1339370*
X-102419Y1367307*
X-99337Y1345361*
X-129962Y1302592*
X-127174Y1311904*
X-119274Y1310004*
X-93934Y1273304*
X-93874Y1278604*
X-133076Y1311004*
X-136874Y1314904*
X-103374Y1240504*
X-113374Y1236504*
X-125374Y1244004*
X-116874Y1159004*
X-127174Y1131504*
X-100274Y1119604*
X-111274Y1130204*
X-106574Y1091404*
X-100674Y1103204*
X-118974Y1091804*
X-100574Y1110404*
X-116074Y1015004*
X-120858Y1021669*
X-127928Y1022904*
X-138777Y1010326*
X-102374Y1018004*
X-118274Y970654*
X-126954Y975604*
X-135574Y970104*
X-95474Y1002604*
X-98416Y980546*
X-105832Y1001546*
X-111374Y1002004*
X-138774Y965104*
X-99374Y938004*
X-93374Y959004*
X-136374Y891704*
X-130736Y583004*
X-136874Y552079*
X-107374Y561004*
X-107874Y525504*
X-108874Y507754*
X-120898Y516425*
X-124996Y520503*
X-125069Y512434*
X-129212Y516483*
X-124898Y516504*
X-108074Y534704*
X-107574Y517804*
X-110874Y539004*
X-130874Y537204*
X-134849Y533104*
X-135174Y499704*
X-119707Y498837*
X-125374Y449004*
X-112207Y470337*
X-138054Y481824*
X-105874Y403804*
X-97374Y358504*
X-128374Y362504*
X-106374Y251504*
Y272004*
X-106874Y261504*
X-117374Y249004*
X-117874Y259004*
X-117374Y269504*
X-127374Y258394*
Y271894*
X-94374Y254894*
Y268394*
X-127374Y243394*
X-119374Y200004*
X-116374Y241504*
X-125374Y236504*
X-127374Y208504*
X-105374Y193004*
X-94374Y242504*
X-94874Y194394*
X-127374Y221394*
X-118374Y167504*
X-96374Y183504*
X-105374Y172504*
X-105874Y182504*
X-94374Y175394*
X-116142Y191204*
X-115642Y179394*
X-127874Y157004*
X-127374Y172004*
X-91874Y98904*
X-121874Y125004*
X-104874Y118004*
X-128374Y132004*
Y118004*
X-116374Y116894*
X-92974Y124004*
X-93574Y116204*
X-89874Y53504*
X-170486Y1530335*
X-151274Y1560304*
X-152274Y1497704*
X-156874Y1446004*
X-182674Y1436304*
X-159374Y1435504*
X-172074Y1426604*
X-157374Y1393904*
X-153104Y1396804*
X-143074Y1402104*
X-184174Y1359869*
X-165074Y1347704*
X-154537Y1334453*
X-156469Y1350204*
X-159209Y1328104*
X-153074Y1323904*
X-170974Y1363787*
X-186891Y1348491*
X-181974Y1315604*
X-161074Y1315304*
X-180874Y1277504*
X-149874Y1267504*
X-166374Y1273504*
X-153374Y1293504*
X-152874Y1256754*
X-175474Y1265204*
X-168374Y1052004*
X-141374Y1015504*
X-147374Y1017004*
X-150974Y961404*
X-169874Y941504*
X-186374Y700004*
X-167648Y554130*
X-143974Y504604*
X-142274Y514204*
X-140874Y520904*
X-173374Y517904*
X-145874Y520004*
X-150274Y468604*
X-144374Y487079*
X-156374Y489004*
X-144374Y317504*
X-146874Y272004*
Y256004*
X-189374Y252004*
X-166374*
X-175374Y252504*
X-189874Y264504*
X-176374Y263504*
X-166374*
X-170874Y271504*
X-182142Y271394*
X-159874*
Y257894*
Y242894*
X-146374Y241004*
X-189874Y242504*
X-191474Y203404*
X-170374Y195504*
X-160374Y197394*
X-181142Y192504*
X-146874Y168004*
X-145874Y144504*
X-176874Y187004*
X-164374Y186504*
X-163374Y170004*
X-174374Y170504*
X-186874Y170004*
X-169874Y178504*
X-180642Y178394*
X-159874*
X-144874Y91004*
X-146874Y117504*
X-146374Y129004*
X-169374Y116004*
X-190974Y130204*
X-180874Y115894*
X-159374Y117394*
X-147735Y79043*
X-197802Y1532704*
X-205374Y1487004*
X-193874Y835504*
X-196874Y536504*
X-192374Y272004*
X-192874Y230004*
X-193374Y164004*
X-193874Y178504*
X-192874Y116004*
G54D230*
G55*
X-104331Y195079D03*
G54D231*
G55*
X-27157Y1661222D03*
X-33774Y246804*
X-65274Y1760604*
X-64774Y1731904*
X-64474Y1776904*
X-40574Y1715004*
X-70874Y1704204*
X-47074Y1624704*
X-89274Y1438004*
X-86274Y1380904*
X-57474Y1395004*
X-69274Y1295104*
X-65274*
X-71974Y1059104*
X-84876Y834007*
X-40774Y307704*
X-103974Y1438004*
X-132774Y1383300*
X-128674*
X-100939Y1374433*
X-105139*
X-100339Y1361533*
X-103074Y1306204*
X-118774Y1087104*
X-110474*
X-127174*
X-130403Y1016160*
X-125403*
X-120403*
X-108374Y548204*
X-99374*
X-91374Y506704*
X-112874Y548204*
X-115374Y481704*
X-178474Y1439404*
X-163474Y1439504*
X-165874Y1393304*
X-178074Y1344804*
X-188239Y1326133*
X-145639Y1309833*
X-162374Y1284704*
X-157374Y1260204*
X-155774Y968804*
X-159974Y968704*
X-171374Y974204*
X-167374*
X-151674Y968704*
X-142874Y560100*
X-142574Y567900*
X-145374Y528204*
G54D232*
G55*
X-29874Y324204D03*
X-29674Y247804*
X-31474Y275704*
X-68174Y1813204*
Y1805204*
Y1789204*
Y1809204*
Y1793204*
X-57774Y1755104*
X-69074Y1751504*
X-68174Y1769204*
X-44074Y1696204*
X-40374Y1647204*
X-82074Y1537204*
X-72274Y1391304*
X-56674Y1052104*
X-79974Y968704*
X-41374Y884904*
X-60674Y198704*
X-99577Y1907002*
X-97074Y1897004*
X-129174Y1531004*
X-89830Y1278039*
X-91974Y1282104*
X-137230Y1276339*
X-137130Y1280439*
Y1284839*
X-124174Y1297904*
X-95270Y1120004*
Y1124404*
Y1115604*
X-95274Y1102804*
Y1111304*
Y1107004*
X-123174Y560304*
X-102574Y517504*
X-120974Y542604*
X-102574Y529504*
X-95574Y484504*
X-140074Y486504*
X-171174Y1422904*
X-173974Y1345804*
X-163603Y1353439*
X-183074Y1267404*
X-163370Y553504*
X-151774Y510104*
X-163374Y545104*
X-163370Y549304*
X-202074Y1529004*
G54D233*
G55*
X-74749Y1293898D03*
X-77309*
X-79869*
Y1287398*
X-74749*
G54D234*
G55*
X-148974Y566808D03*
Y558408*
X-166474Y522100*
Y530500*
G54D235*
G55*
X-124049Y1122200D03*
X-121494*
X-118934*
X-116374*
X-113814*
X-111254*
X-108699*
Y1100000*
X-111254*
X-113814*
X-116374*
X-118934*
X-121494*
X-124049*
X-121834Y983304*
X-124394*
X-126954*
X-129514*
Y1005504*
X-126954*
X-124394*
X-121834*
X-163699Y1236200*
X-166254*
X-168814*
X-171374*
X-173934*
X-176494*
X-179049*
Y1258400*
X-176494*
X-173934*
X-171374*
X-168814*
X-166254*
X-163699*
X-145214Y1009004*
X-147774*
X-150334*
X-152894*
X-155454*
X-158014*
X-160574*
X-163134*
Y986804*
X-160574*
X-158014*
X-155454*
X-152894*
X-150334*
X-147774*
X-145214*
G54D236*
G55*
X-55372Y1724005D03*
X-60074Y1724004*
X-70574Y1708704*
X-52974Y1385604*
X-89374Y1235304*
X-71076Y834557*
X-111774Y1486304*
X-104174Y1405204*
X-136939Y1289810*
X-131339*
X-132774Y1240304*
X-102374Y986204*
X-138674Y987104*
X-154574Y1486204*
X-171174Y1266404*
X-152174Y851604*
X-156876Y851557*
X-141374Y491704*
G54D237*
G55*
X-75872Y1912001D03*
X-75272Y1897501*
X-68874Y1728504*
X-69474Y1757204*
X-68474Y1773504*
X-62174Y1705204*
X-66174*
X-45074Y1711604*
X-70474Y1719304*
X-81574Y1425204*
X-86474Y1394004*
X-81774Y1409704*
X-46874Y1387204*
X-85074Y1262604*
X-84874Y1237704*
X-51274Y1072404*
X-89272Y842401*
X-71372Y844701*
X-71072Y826501*
X-56174Y212804*
X-124674Y1379908*
X-136774*
X-99174Y1395304*
X-137209Y1306475*
X-112774Y1306304*
X-123474Y1308304*
X-124174Y1297904*
X-127474Y1136704*
X-119074*
X-110774Y1136708*
X-129545Y1028748*
X-125174Y1028804*
X-118374*
X-139374Y1020704*
X-131174Y967204*
X-127174*
X-122674*
X-106874Y988804*
X-130874Y544304*
X-135374*
X-103374Y504304*
X-125874Y544304*
X-103474Y544804*
X-136874Y466804*
X-132874*
X-128874*
X-124874*
X-120874*
X-116874*
X-101374Y489304*
X-144653Y1425433*
X-153174Y1386304*
X-161374Y1398504*
X-144553Y1411333*
X-159209Y1332675*
X-156309Y1315175*
X-141409Y1306475*
X-152109Y1315175*
X-175574Y1268904*
X-162374Y1265804*
X-166374*
X-156874Y1019304*
X-160874*
X-164874*
X-152874*
X-148374Y1020704*
X-143874*
X-146974Y965404*
X-142874Y965304*
X-164505Y537423*
X-168705Y538223*
X-160205Y537423*
X-173274Y538304*
X-158874Y477304*
X-154374*
X-149874*
X-144874Y466804*
X-140874*
X-145774Y477404*
X-156374Y494404*
G54D238*
G55*
X-155374Y531254D03*
X-151499Y523754*
X-159249*
G54D239*
G55*
X-59624Y1277944D03*
Y1280504*
Y1283064*
X-66124*
Y1277944*
X-44124*
Y1280504*
Y1283064*
X-50624*
Y1277944*
G54D240*
G55*
X-121674Y571364D03*
Y568804*
Y566244*
X-114274*
Y568804*
Y571364*
G54D241*
G55*
X-56074Y208204D03*
X-94674Y1430704*
X-103974*
X-106474Y1415204*
X-115474Y1374804*
X-120774Y1365004*
X-178474Y1432104*
X-168774Y1432004*
G54D242*
G55*
X-75872Y1915401D03*
X-75272Y1900901*
X-68874Y1731904*
X-69474Y1760604*
X-68474Y1776904*
X-62174Y1708604*
X-66174*
X-45074Y1715004*
X-70474Y1722704*
X-81574Y1428604*
X-86474Y1397404*
X-81774Y1413104*
X-46874Y1390604*
X-85074Y1266004*
X-84874Y1241104*
X-51274Y1075804*
X-89272Y845801*
X-71372Y848101*
X-71072Y829901*
X-56174Y216204*
X-124674Y1383308*
X-136774*
X-99174Y1398704*
X-137209Y1309875*
X-112774Y1309704*
X-123474Y1311704*
X-124174Y1301304*
X-127474Y1140104*
X-119074*
X-110774Y1140108*
X-129545Y1032148*
X-125174Y1032204*
X-118374*
X-139374Y1024104*
X-131174Y970604*
X-127174*
X-122674*
X-106874Y992204*
X-130874Y547704*
X-135374*
X-103374Y507704*
X-125874Y547704*
X-103474Y548204*
X-136874Y470204*
X-132874*
X-128874*
X-124874*
X-120874*
X-116874*
X-101374Y492704*
X-144653Y1428833*
X-153174Y1389704*
X-161374Y1401904*
X-144553Y1414733*
X-159209Y1336075*
X-156309Y1318575*
X-152109*
X-141409Y1309875*
X-162374Y1269204*
X-175574Y1272304*
X-166374Y1269204*
X-156874Y1022704*
X-160874*
X-164874*
X-152874*
X-148374Y1024104*
X-143874*
X-146974Y968804*
X-142874Y968704*
X-164505Y540823*
X-168705Y541623*
X-160205Y540823*
X-173274Y541704*
X-158874Y480704*
X-154374*
X-149874*
X-144874Y470204*
X-140874*
X-145774Y480804*
X-156374Y497804*
G54D243*
G55*
X-40233Y288004D03*
X-68515*
G54D244*
G55*
X-64074Y1715704D03*
X-47874Y1674204*
X-81374Y1377504*
X-84474Y981904*
X-75474Y943504*
X-91721Y1907106*
X-124774Y1588404*
X-99403Y1434825*
X-114974Y982504*
Y977704*
X-102674Y513004*
X-114674Y494004*
X-173774Y1436404*
X-173574Y1415204*
X-189895Y1354969*
X-168174Y506004*
G54D245*
G55*
X-57774Y1084704D03*
Y1073704*
X-71674Y981904*
Y992904*
X-46874Y946004*
Y935004*
X-103874Y1037504*
Y1026504*
X-154874Y1236504*
Y1247504*
G54D246*
G55*
X-150174Y496704D03*
Y487704*
G54D247*
G55*
X-79676Y1911957D03*
X-79274Y1896750*
X-83074Y1227004*
X-83574Y1249404*
X-61674Y955404*
X-111374Y1371004*
X-154239Y1357183*
G54D248*
G55*
X-59674Y208204D03*
X-98274Y1430704*
X-107574*
X-110074Y1415204*
X-119074Y1374804*
X-124374Y1365004*
X-182074Y1432104*
X-172374Y1432004*
G54D249*
G55*
X-132874Y559050D03*
X-128999Y566550*
X-136749*
G54D250*
G55*
X-77509Y1606604D03*
X-118609Y1606704*
X-107239Y1606604*
X-148339Y1606704*
X-165709Y460804*
X-195439*
G54D251*
G55*
X-71775Y1018904D03*
X-94573*
G54D21*
G55*
X-104331Y220669D03*
Y145473*
X-186811Y639764*
X-169291Y220669*
Y145473*
G54D252*
G55*
X-119756Y506904D03*
X-122315*
X-124874*
X-127433*
X-129992*
Y526104*
X-127433*
X-124874*
X-122315*
X-119756*
G54D253*
G55*
X-76874Y1528504D03*
X-81874*
X-86874*
X-68274Y392904*
X-73274*
X-78274*
X-83274*
X-104374Y1529004*
X-109374*
X-114374*
X-119374*
X-91874Y1528504*
X-136374Y393004*
X-101374*
X-106374*
X-111374*
X-116374*
X-148874Y1529004*
X-153874*
X-158874*
X-163874*
X-176874*
X-181874*
X-186874*
X-191874*
X-170374Y393004*
X-175374*
X-180374*
X-185374*
X-141374*
X-146374*
X-151374*
G54D254*
G55*
X-169291Y195079D03*
G54D255*
G55*
X-134474Y511386D03*
Y513945*
Y516504*
Y519063*
Y521622*
X-115274*
Y519063*
Y516504*
Y513945*
Y511386*
G54D256*
G55*
X-97209Y1423754D03*
X-95244*
X-93274*
X-91304*
X-89339*
Y1407454*
X-91304*
X-93274*
X-95244*
X-97209*
X-116584Y1355875*
X-118549*
X-120519*
X-122489*
X-124454*
X-126424*
X-128394*
X-130364*
X-132329*
X-134299*
X-136269*
X-138234*
Y1322475*
X-136269*
X-134299*
X-132329*
X-130364*
X-128394*
X-126424*
X-124454*
X-122489*
X-120519*
X-118549*
X-116584*
X-161009Y1425554*
X-159044*
X-157074*
X-155104*
X-153139*
Y1409254*
X-155104*
X-157074*
X-159044*
X-161009*
G54D257*
G55*
X-85274Y988454D03*
Y992204*
Y995954*
X-95874*
Y992204*
Y988454*
G54D258*
G55*
X-124874Y516504D03*
G54D259*
G55*
X-110709Y1328350D03*
Y1330315*
Y1332285*
Y1334255*
Y1336220*
Y1338190*
Y1340160*
Y1342130*
Y1344095*
Y1346065*
Y1348035*
Y1350000*
X-144109*
Y1348035*
Y1346065*
Y1344095*
Y1342130*
Y1340160*
Y1338190*
Y1336220*
Y1334255*
Y1332285*
Y1330315*
Y1328350*
G54D196*
G55*
X-157874Y1904004D03*
X-160374Y62504*
G54D198*
G55*
X401977Y1657822D03*
X395360Y243404*
X363860Y1757204*
X364360Y1728504*
X364660Y1773504*
X388560Y1711604*
X358260Y1700804*
X382060Y1621304*
X339860Y1434604*
X342860Y1377504*
X371660Y1391604*
X359860Y1291704*
X363860*
X357160Y1055704*
X344258Y830607*
X388360Y304304*
X325160Y1434604*
X296360Y1379900*
X300460*
X328195Y1371033*
X323995*
X328795Y1358133*
X326060Y1302804*
X310360Y1083704*
X318660*
X301960*
X298731Y1012760*
X303731*
X308731*
X320760Y544804*
X329760*
X337760Y503304*
X316260Y544804*
X313760Y478304*
X250660Y1436004*
X265660Y1436104*
X263260Y1389904*
X251060Y1341404*
X240895Y1322733*
X283495Y1306433*
X266760Y1281304*
X271760Y1256804*
X273360Y965404*
X269160Y965304*
X257760Y970804*
X261760*
X277460Y965304*
X286260Y556700*
X286560Y564500*
X283760Y524804*
G54D199*
G55*
X392160Y1647204D03*
X391160Y884904*
X402660Y324204*
X402860Y247804*
X401060Y275704*
X364360Y1813204*
Y1805204*
Y1789204*
Y1809204*
Y1793204*
X374760Y1755104*
X363460Y1751504*
X364360Y1769204*
X388460Y1696204*
X350460Y1537204*
X360260Y1391304*
X342704Y1278039*
X340560Y1282104*
X375860Y1052104*
X352560Y968704*
X371860Y198704*
X332957Y1907002*
X335460Y1897004*
X303360Y1531004*
X295304Y1276339*
X295404Y1280439*
Y1284839*
X308360Y1297904*
X337264Y1120004*
Y1124404*
Y1115604*
X337260Y1102804*
Y1111304*
Y1107004*
X309360Y560304*
X329960Y517504*
X311560Y542604*
X329960Y529504*
X336960Y484504*
X292460Y486504*
X261360Y1422904*
X258560Y1345804*
X268931Y1353439*
X249460Y1267404*
X269164Y553504*
X280760Y510104*
X269160Y545104*
X269164Y549304*
X230460Y1529004*
G54D12*
G55*
X391339Y1943701D03*
Y1857087*
Y1510473*
Y1423858*
Y1250630*
Y1164016*
X391260Y804504*
X391339Y717874*
Y544646*
Y458032*
Y111418*
Y24803*
G54D200*
G55*
X393260Y198604D03*
X345560Y1897004*
X363060Y1306204*
Y1310904*
X372560Y203804*
X311060Y1199404*
Y1204404*
X321560Y910104*
Y914804*
X238960Y315804*
Y320504*
X279413Y89806*
X279460Y84804*
G54D201*
G55*
X398360Y1570704D03*
Y1550204*
X402160Y1301504*
X340160Y1570004*
X373560Y1570704*
X340160Y1549504*
X373560Y1550204*
X377360Y1301504*
X347660Y1170104*
X357560Y877904*
X384660Y417004*
X359860*
X308160Y1880004*
X315360Y1570004*
Y1549504*
X322860Y1170104*
X332760Y877904*
X283360Y1880004*
X235960Y1570604*
X260760*
X236060Y1611804*
X260860*
X235860Y1591604*
X260660*
X235960Y1550104*
X260760*
X236360Y437004*
X261160*
X236260Y416904*
X261060*
G54D202*
G55*
X399910Y187504D03*
X343307Y1914002*
X349610Y1384504*
X362910*
X376210Y1375504*
X362910*
X339410Y1253104*
X339910Y1228104*
X361110Y956704*
X347810*
X356810Y936404*
X343510*
X386610Y187504*
X330007Y1914002*
X325410Y1900004*
X312110*
X326110Y1253104*
X326610Y1228104*
G54D203*
G55*
X349458Y1915557D03*
X349860Y1900350*
X346060Y1230604*
X345560Y1253004*
X367460Y959004*
X317760Y1374604*
X274895Y1360783*
G54D13*
G55*
X405354Y1920394D03*
Y1910394*
Y1900394*
Y1890394*
Y1880394*
Y1487165*
Y1477165*
Y1467165*
Y1457165*
Y1447165*
Y1227323*
Y1217323*
Y1207323*
Y1197323*
Y1187323*
Y781181*
Y771181*
Y761181*
Y751181*
Y741181*
Y521339*
Y511339*
Y501339*
Y491339*
Y481339*
Y88110*
Y78110*
Y68110*
Y58110*
Y48110*
X292323Y189685*
X302323*
X256260Y578004*
Y588004*
Y598004*
X282323Y189685*
G54D204*
G55*
X390960Y180704D03*
X356760Y1395504*
X350060Y824004*
X339360Y1002304*
X334260Y825504*
X326460Y537004*
Y533604*
Y525704*
X257860Y1419204*
X276960Y1273004*
X287960Y536504*
G54D14*
G55*
X393701Y1811024D03*
Y1338583*
X403544Y629921*
X393701Y157481*
X242126Y1889764*
X242127Y1397638*
X242126Y807087*
Y78740*
G54D17*
G55*
X374016Y1900394D03*
Y1467166*
Y1207323*
Y761181*
Y501339*
Y68111*
G54D205*
G55*
X349260Y1494956D03*
Y1477052*
X331260Y1494956*
Y1477052*
X245260Y1495456*
Y1477552*
X263260Y1495456*
Y1477552*
G54D206*
G55*
X391260Y1397704D03*
X396960Y862504*
X402660Y328304*
X401360Y198904*
X353960Y1905004*
X364360Y1797204*
Y1785204*
Y1801204*
Y1781204*
X363460Y1747504*
X374760Y1751104*
X388578Y1704287*
X364360Y1688504*
X342716Y1273869*
X341260Y1286304*
X355960Y1238504*
X352560Y964204*
X361660Y947904*
X348960Y943104*
X348860Y947604*
X383260Y872504*
X352460Y793404*
X390560Y194104*
X386260Y180304*
X322560Y1418904*
X337560Y1398604*
X329960Y1297504*
X305660Y1308304*
X316360Y1306304*
X333460Y1260604*
X334960Y1235104*
X317160Y560404*
X291460Y540204*
X329960Y522004*
X311560Y546904*
X271160Y1537704*
X275960Y1400504*
X268460Y1381504*
X258560Y1341804*
X246960Y1344204*
X273256Y574504*
X280760Y502104*
Y506104*
X281060Y515204*
X263960Y510504*
G54D207*
G55*
X397160Y1277604D03*
X392360*
X347160Y1392304*
X355625Y1274598*
X350725*
X339260Y1260304*
X349060Y1257504*
X354060*
X350460Y987104*
X357060Y964404*
X339862Y830751*
X328960Y1090050*
X333760*
X327260Y1005704*
X317760Y988704*
X291360Y976004*
X280860Y1396104*
X262725Y1358825*
G54D208*
G55*
X394560Y180704D03*
X360360Y1395504*
X342960Y1002304*
X353660Y824004*
X337860Y825504*
X330060Y537004*
Y533604*
X291560Y536504*
X330060Y525704*
X261460Y1419204*
X280560Y1273004*
G54D209*
G55*
X351058Y830157D03*
Y843457*
X379660Y200954*
Y214254*
X332758Y832257*
Y845557*
G54D18*
G55*
X340551Y1849095D03*
Y1639095*
X271654Y1849095*
Y1639095*
G54D15*
G55*
X389961Y1737638D03*
Y1747638*
Y1757638*
Y1629941*
Y1609941*
Y1619941*
Y1064587*
Y1044587*
Y1054587*
Y913917*
Y923917*
Y903917*
Y348563*
Y358563*
Y338563*
Y210866*
Y220866*
Y230866*
G54D71*
G55*
X347360Y1418404D03*
X288525Y1375075*
X295425Y1374875*
X328289Y1351169*
X289325Y1366575*
X316260Y1365304*
X319360Y1314404*
X304160Y538404*
X284489Y1419983*
X276931Y1369739*
X281125Y1375275*
X260560Y1352604*
X270231Y1340939*
X281331Y1364339*
X264560Y1341704*
X242260Y1262004*
X273660Y973904*
X267260Y974004*
X279260*
G54D210*
G55*
X386260Y1387204D03*
X363160Y937704*
X333860Y1394404*
X271760Y1389904*
X256660Y1360004*
X270760Y1269304*
G54D211*
G55*
X331825Y1325875D03*
Y1333475*
X331760Y506804*
Y499204*
X249160Y1419404*
Y1427004*
X251160Y1360904*
Y1353304*
X268995Y1359533*
Y1367133*
X254260Y510804*
Y503204*
G54D212*
G55*
X341060Y491004D03*
X313660Y1410204*
X306060*
X333460Y491004*
X314490Y487864*
X322090*
X237560Y362004*
X240560Y327504*
X229960Y362004*
X232960Y327504*
G54D213*
G55*
X393789Y1705951D03*
X401539*
X397664Y1713451*
X396335Y1663154*
X392460Y1655654*
X393635Y319454*
X393968Y253636*
X401718*
X397843Y261136*
X388585Y1663154*
X366443Y1066136*
X362568Y1058636*
X370318*
X342508Y355207*
Y348801*
X385885Y319454*
X389760Y326954*
X289735Y1245954*
X312008Y355207*
Y348801*
X279635Y1286254*
X271885*
X275760Y1278754*
X281985Y1245954*
X285860Y1238454*
X273235Y567050*
X265485*
X269360Y559550*
X255766Y531035*
X248016*
X251891Y523535*
X282566Y546235*
X274816*
X278691Y538735*
X283508Y355207*
Y348801*
X256008Y355207*
Y348801*
G54D19*
G55*
X340551Y1829095D03*
Y1659095*
X271654Y1829095*
Y1659095*
G54D214*
G55*
X349060Y1882304D03*
X348658Y1210607*
X357560Y918404*
X322260Y1882304*
X321858Y1210607*
X330760Y918404*
G54D215*
G55*
X397160Y1283204D03*
X392360*
X347160Y1397904*
X339260Y1265904*
X355625Y1280198*
X350725*
X349060Y1263104*
X354060*
X350460Y992704*
X357060Y970004*
X339862Y836351*
X328960Y1095650*
X333760*
X327260Y1011304*
X317760Y994304*
X291360Y981604*
X280860Y1401704*
X262725Y1364425*
G54D216*
G55*
X343013Y1907106D03*
X370660Y1715704*
X386860Y1674204*
X353360Y1377504*
X350260Y981904*
X359260Y943504*
X309960Y1588404*
X335331Y1434825*
X319760Y982504*
Y977704*
X332060Y513004*
X320060Y494004*
X260960Y1436404*
X261160Y1415204*
X244839Y1354969*
X266560Y506004*
G54D217*
G55*
X386260Y1383604D03*
X363160Y934104*
X333860Y1390804*
X271760Y1386304*
X256660Y1356404*
X270760Y1265704*
G54D218*
G55*
X342360Y469804D03*
Y445004*
X296962Y60201*
Y85001*
X275462Y817201*
Y842001*
G54D219*
G55*
X328054Y1291089D03*
Y1286089*
Y1281089*
Y1276089*
X307954*
Y1281089*
Y1286089*
Y1291089*
G54D220*
G55*
X249890Y1333685D03*
X261460*
X249890Y1322665*
X261460*
G54D221*
G55*
X393360Y1721604D03*
X395960Y1640004*
X405060Y311404*
X394060*
X405460Y269304*
X394460*
X382360Y1721604*
X384960Y1640004*
X296564Y576204*
X315260Y581004*
X304260*
X285564Y576204*
X267260Y581004*
X278260*
G54D222*
G55*
X393560Y862504D03*
X399260Y328304*
X397960Y198904*
X350560Y1905004*
X360960Y1797204*
Y1785204*
Y1801204*
Y1781204*
X360060Y1747504*
X371360Y1751104*
X385178Y1704287*
X360960Y1688504*
X387860Y1397704*
X352560Y1238504*
X349160Y964204*
X358260Y947904*
X345560Y943104*
X345460Y947604*
X379860Y872504*
X349060Y793404*
X387160Y194104*
X382860Y180304*
X319160Y1418904*
X334160Y1398604*
X339316Y1273869*
X326560Y1297504*
X302260Y1308304*
X312960Y1306304*
X337860Y1286304*
X330060Y1260604*
X331560Y1235104*
X313760Y560404*
X326560Y522004*
X308160Y546904*
X267760Y1537704*
X272560Y1400504*
X265060Y1381504*
X255160Y1341804*
X243560Y1344204*
X269856Y574504*
X288060Y540204*
X277360Y502104*
Y506104*
X277660Y515204*
X260560Y510504*
G54D20*
G55*
X340551Y1806615D03*
Y1796615*
Y1786615*
Y1776615*
Y1764095*
Y1754095*
Y1744095*
Y1734095*
Y1724095*
Y1711575*
Y1701575*
Y1691575*
Y1681575*
X310551Y1806615*
Y1796615*
X320551Y1806615*
Y1796615*
X330551Y1806615*
Y1796615*
X310551Y1786615*
Y1776615*
X320551Y1786615*
Y1776615*
X330551Y1786615*
Y1776615*
X310551Y1764095*
Y1754095*
Y1744095*
Y1734095*
Y1724095*
X320551Y1764095*
Y1754095*
Y1744095*
Y1734095*
Y1724095*
X330551Y1764095*
Y1754095*
Y1744095*
Y1734095*
Y1724095*
X310551Y1711575*
Y1701575*
X320551Y1711575*
Y1701575*
X330551Y1711575*
Y1701575*
X310551Y1691575*
Y1681575*
X320551Y1691575*
Y1681575*
X330551Y1691575*
Y1681575*
X241654Y1806615*
Y1796615*
X251654Y1806615*
Y1796615*
X261654Y1806615*
Y1796615*
X271654Y1806615*
Y1796615*
X241654Y1786615*
Y1776615*
X251654Y1786615*
Y1776615*
X261654Y1786615*
Y1776615*
X271654Y1786615*
Y1776615*
X241654Y1764095*
Y1754095*
Y1744095*
Y1734095*
Y1724095*
X251654Y1764095*
Y1754095*
Y1744095*
Y1734095*
Y1724095*
X261654Y1764095*
Y1754095*
Y1744095*
Y1734095*
Y1724095*
X271654Y1764095*
Y1754095*
Y1744095*
Y1734095*
Y1724095*
X241654Y1711575*
Y1701575*
X251654Y1711575*
Y1701575*
X261654Y1711575*
Y1701575*
X271654Y1711575*
Y1701575*
X241654Y1691575*
Y1681575*
X251654Y1691575*
Y1681575*
X261654Y1691575*
Y1681575*
X271654Y1691575*
Y1681575*
G54D223*
G55*
X350010Y355207D03*
Y348801*
X319510Y355207*
Y348801*
X291010Y355207*
Y348801*
X263510Y355207*
Y348801*
G54D224*
G55*
X286551Y1258004D03*
X303969*
G54D225*
G55*
X396892Y875421D03*
X389392Y879296*
Y871546*
X309242Y1401513*
Y1393763*
X316742Y1397638*
X309242Y712536*
Y704786*
X316742Y708661*
G54D226*
G55*
X373762Y1729605D03*
X369060Y1729604*
X358560Y1714304*
X376160Y1391204*
X339760Y1240904*
X358058Y840157*
X317360Y1491904*
X324960Y1410804*
X292195Y1295410*
X297795*
X296360Y1245904*
X326760Y991804*
X290460Y992704*
X274560Y1491804*
X257960Y1272004*
X276960Y857204*
X272258Y857157*
X287760Y497304*
G54D227*
G55*
X339960Y1897004D03*
X357460Y1306204*
Y1310904*
X366960Y203804*
X387660Y198604*
X305460Y1199404*
Y1204404*
X315960Y910104*
Y914804*
X273813Y89806*
X273860Y84804*
X233360Y315804*
Y320504*
G54D228*
G55*
X240795Y1337133D03*
Y1333533*
G54D229*
G55*
X347857Y1335002D03*
Y1361802*
X299163Y843206*
Y816406*
X322763Y85306*
Y58506*
G54D16*
G55*
X402660Y1719404D03*
X393360Y1699033*
X401250Y1665522*
X410260Y1390504*
X393960Y1375504*
X394160Y1390404*
X396760Y866504*
X401204Y194315*
X377360Y1831304*
X385060Y1649804*
X358060Y1583404*
X358860Y1537904*
X358360Y1555604*
X359560Y1546604*
X350360Y1541304*
X355260Y1458004*
X343860Y1432204*
X350860Y1403004*
X371595Y1325571*
X377923Y1318359*
X384260Y1363504*
X364060Y1300620*
X356260Y1193504*
Y1202504*
X378160Y1102404*
X344760Y1068004*
X355360Y1068504*
X357160Y1063704*
X348260Y1002504*
X354360Y999404*
X361260Y1001704*
X339760Y982604*
X369760Y994404*
X384060Y876804*
X369160Y835804*
X350260Y735904*
X388260Y393504*
X367960Y359304*
X356860Y362604*
X358960Y327204*
X361760Y341004*
X388360Y312204*
X359760Y252004*
X348760Y251504*
Y269504*
X388260Y250004*
X388311Y259053*
X342260Y202004*
X349760Y208504*
X348760Y235504*
X340260Y166504*
X348260Y155504*
X349260Y170504*
X364260Y163004*
X345760Y130004*
X348260Y121504*
X348760Y138504*
X355260Y51504*
X302760Y1526504*
X298760Y1539504*
X296160Y1559604*
X306260Y1482404*
X314760Y1499004*
X305760Y1491804*
X324360Y1426904*
X321460Y1422904*
X300460Y1369804*
X309242Y1383604*
X314922Y1388008*
X302695Y1375658*
X337641Y1386762*
X338360Y1394004*
X319460Y1411104*
X324760Y1400904*
X321682Y1362733*
X328197Y1339370*
X326715Y1367307*
X329797Y1345361*
X299172Y1302592*
X301960Y1311904*
X309860Y1310004*
X335200Y1273304*
X335260Y1278604*
X296058Y1311004*
X292260Y1314904*
X325760Y1240504*
X315760Y1236504*
X303760Y1244004*
X312260Y1159004*
X301960Y1131504*
X328860Y1119604*
X317860Y1130204*
X322560Y1091404*
X328460Y1103204*
X310160Y1091804*
X328560Y1110404*
X313060Y1015004*
X308276Y1021669*
X301206Y1022904*
X290357Y1010326*
X326760Y1018004*
X310860Y970654*
X302180Y975604*
X293560Y970104*
X333660Y1002604*
X330718Y980546*
X323302Y1001546*
X317760Y1002004*
X290360Y965104*
X329760Y938004*
X335760Y959004*
X292760Y891704*
X298398Y583004*
X292260Y552079*
X321760Y561004*
X321260Y525504*
X320260Y507754*
X308236Y516425*
X304138Y520503*
X304065Y512434*
X299922Y516483*
X304236Y516504*
X321060Y534704*
X321560Y517804*
X318260Y539004*
X298260Y537204*
X294285Y533104*
X293960Y499704*
X309427Y498837*
X303760Y449004*
X316927Y470337*
X291080Y481824*
X323260Y403804*
X331760Y358504*
X300760Y362504*
X322760Y251504*
Y272004*
X322260Y261504*
X311760Y249004*
X311260Y259004*
X311760Y269504*
X301760Y258394*
Y271894*
X334760Y254894*
Y268394*
X301760Y243394*
X309760Y200004*
X312760Y241504*
X303760Y236504*
X301760Y208504*
X323760Y193004*
X334760Y242504*
X334260Y194394*
X301760Y221394*
X310760Y167504*
X332760Y183504*
X323760Y172504*
X323260Y182504*
X334760Y175394*
X312992Y191204*
X313492Y179394*
X301260Y157004*
X301760Y172004*
X337260Y98904*
X307260Y125004*
X324260Y118004*
X300760Y132004*
Y118004*
X312760Y116894*
X336160Y124004*
X335560Y116204*
X339260Y53504*
X258648Y1530335*
X277860Y1560304*
X276860Y1497704*
X272260Y1446004*
X246460Y1436304*
X269760Y1435504*
X257060Y1426604*
X271760Y1393904*
X276030Y1396804*
X286060Y1402104*
X244960Y1359869*
X264060Y1347704*
X274597Y1334453*
X272665Y1350204*
X269925Y1328104*
X276060Y1323904*
X258160Y1363787*
X242243Y1348491*
X247160Y1315604*
X268060Y1315304*
X248260Y1277504*
X279260Y1267504*
X262760Y1273504*
X275760Y1293504*
X276260Y1256754*
X253660Y1265204*
X260760Y1052004*
X287760Y1015504*
X281760Y1017004*
X278160Y961404*
X259260Y941504*
X242760Y700004*
X261486Y554130*
X285160Y504604*
X286860Y514204*
X288260Y520904*
X255760Y517904*
X283260Y520004*
X278860Y468604*
X284760Y487079*
X272760Y489004*
X284760Y317504*
X282260Y272004*
Y256004*
X239760Y252004*
X262760*
X253760Y252504*
X239260Y264504*
X252760Y263504*
X262760*
X258260Y271504*
X246992Y271394*
X269260*
Y257894*
Y242894*
X282760Y241004*
X239260Y242504*
X237660Y203404*
X258760Y195504*
X268760Y197394*
X247992Y192504*
X282260Y168004*
X283260Y144504*
X252260Y187004*
X264760Y186504*
X265760Y170004*
X254760Y170504*
X242260Y170004*
X259260Y178504*
X248492Y178394*
X269260*
X284260Y91004*
X282260Y117504*
X282760Y129004*
X259760Y116004*
X238160Y130204*
X248260Y115894*
X269760Y117394*
X281399Y79043*
X231332Y1532704*
X223760Y1487004*
X235260Y835504*
X232260Y536504*
X236760Y272004*
X236260Y230004*
X235760Y164004*
X235260Y178504*
X236260Y116004*
G54D230*
G55*
X324803Y195079D03*
G54D231*
G55*
X401977Y1661222D03*
X395360Y246804*
X363860Y1760604*
X364360Y1731904*
X364660Y1776904*
X388560Y1715004*
X358260Y1704204*
X382060Y1624704*
X339860Y1438004*
X342860Y1380904*
X371660Y1395004*
X359860Y1295104*
X363860*
X357160Y1059104*
X344258Y834007*
X388360Y307704*
X325160Y1438004*
X296360Y1383300*
X300460*
X328195Y1374433*
X323995*
X328795Y1361533*
X326060Y1306204*
X310360Y1087104*
X318660*
X301960*
X298731Y1016160*
X303731*
X308731*
X320760Y548204*
X329760*
X337760Y506704*
X316260Y548204*
X313760Y481704*
X250660Y1439404*
X265660Y1439504*
X263260Y1393304*
X251060Y1344804*
X240895Y1326133*
X283495Y1309833*
X266760Y1284704*
X271760Y1260204*
X273360Y968804*
X269160Y968704*
X257760Y974204*
X261760*
X277460Y968704*
X286260Y560100*
X286560Y567900*
X283760Y528204*
G54D232*
G55*
X399260Y324204D03*
X399460Y247804*
X397660Y275704*
X360960Y1813204*
Y1805204*
Y1789204*
Y1809204*
Y1793204*
X371360Y1755104*
X360060Y1751504*
X360960Y1769204*
X385060Y1696204*
X388760Y1647204*
X347060Y1537204*
X356860Y1391304*
X372460Y1052104*
X349160Y968704*
X387760Y884904*
X368460Y198704*
X329557Y1907002*
X332060Y1897004*
X299960Y1531004*
X339304Y1278039*
X337160Y1282104*
X291904Y1276339*
X292004Y1280439*
Y1284839*
X304960Y1297904*
X333864Y1120004*
Y1124404*
Y1115604*
X333860Y1102804*
Y1111304*
Y1107004*
X305960Y560304*
X326560Y517504*
X308160Y542604*
X326560Y529504*
X333560Y484504*
X289060Y486504*
X257960Y1422904*
X255160Y1345804*
X265531Y1353439*
X246060Y1267404*
X265764Y553504*
X277360Y510104*
X265760Y545104*
X265764Y549304*
X227060Y1529004*
G54D233*
G55*
X354385Y1293898D03*
X351825*
X349265*
Y1287398*
X354385*
G54D234*
G55*
X280160Y566808D03*
Y558408*
X262660Y522100*
Y530500*
G54D235*
G55*
X305085Y1122200D03*
X307640*
X310200*
X312760*
X315320*
X317880*
X320435*
Y1100000*
X317880*
X315320*
X312760*
X310200*
X307640*
X305085*
X307300Y983304*
X304740*
X302180*
X299620*
Y1005504*
X302180*
X304740*
X307300*
X265435Y1236200*
X262880*
X260320*
X257760*
X255200*
X252640*
X250085*
Y1258400*
X252640*
X255200*
X257760*
X260320*
X262880*
X265435*
X283920Y1009004*
X281360*
X278800*
X276240*
X273680*
X271120*
X268560*
X266000*
Y986804*
X268560*
X271120*
X273680*
X276240*
X278800*
X281360*
X283920*
G54D236*
G55*
X373762Y1724005D03*
X369060Y1724004*
X358560Y1708704*
X376160Y1385604*
X339760Y1235304*
X358058Y834557*
X317360Y1486304*
X324960Y1405204*
X292195Y1289810*
X297795*
X296360Y1240304*
X326760Y986204*
X290460Y987104*
X274560Y1486204*
X257960Y1266404*
X276960Y851604*
X272258Y851557*
X287760Y491704*
G54D237*
G55*
X353262Y1912001D03*
X353862Y1897501*
X360260Y1728504*
X359660Y1757204*
X360660Y1773504*
X366960Y1705204*
X362960*
X384060Y1711604*
X358660Y1719304*
X347560Y1425204*
X342660Y1394004*
X347360Y1409704*
X382260Y1387204*
X344060Y1262604*
X344260Y1237704*
X377860Y1072404*
X339862Y842401*
X357762Y844701*
X358062Y826501*
X372960Y212804*
X304460Y1379908*
X292360*
X329960Y1395304*
X291925Y1306475*
X316360Y1306304*
X305660Y1308304*
X304960Y1297904*
X301660Y1136704*
X310060*
X318360Y1136708*
X299589Y1028748*
X303960Y1028804*
X310760*
X289760Y1020704*
X297960Y967204*
X301960*
X306460*
X322260Y988804*
X298260Y544304*
X293760*
X325760Y504304*
X303260Y544304*
X325660Y544804*
X292260Y466804*
X296260*
X300260*
X304260*
X308260*
X312260*
X327760Y489304*
X284481Y1425433*
X275960Y1386304*
X267760Y1398504*
X284581Y1411333*
X269925Y1332675*
X272825Y1315175*
X287725Y1306475*
X277025Y1315175*
X253560Y1268904*
X266760Y1265804*
X262760*
X272260Y1019304*
X268260*
X264260*
X276260*
X280760Y1020704*
X285260*
X282160Y965404*
X286260Y965304*
X264629Y537423*
X260429Y538223*
X268929Y537423*
X255860Y538304*
X270260Y477304*
X274760*
X279260*
X284260Y466804*
X288260*
X283360Y477404*
X272760Y494404*
G54D238*
G55*
X273760Y531254D03*
X277635Y523754*
X269885*
G54D239*
G55*
X369510Y1277944D03*
Y1280504*
Y1283064*
X363010*
Y1277944*
X385010*
Y1280504*
Y1283064*
X378510*
Y1277944*
G54D240*
G55*
X307460Y571364D03*
Y568804*
Y566244*
X314860*
Y568804*
Y571364*
G54D241*
G55*
X373060Y208204D03*
X334460Y1430704*
X325160*
X322660Y1415204*
X313660Y1374804*
X308360Y1365004*
X250660Y1432104*
X260360Y1432004*
G54D242*
G55*
X353262Y1915401D03*
X353862Y1900901*
X360260Y1731904*
X359660Y1760604*
X360660Y1776904*
X366960Y1708604*
X362960*
X384060Y1715004*
X358660Y1722704*
X347560Y1428604*
X342660Y1397404*
X347360Y1413104*
X382260Y1390604*
X344060Y1266004*
X344260Y1241104*
X377860Y1075804*
X339862Y845801*
X357762Y848101*
X358062Y829901*
X372960Y216204*
X304460Y1383308*
X292360*
X329960Y1398704*
X291925Y1309875*
X316360Y1309704*
X305660Y1311704*
X304960Y1301304*
X301660Y1140104*
X310060*
X318360Y1140108*
X299589Y1032148*
X303960Y1032204*
X310760*
X289760Y1024104*
X297960Y970604*
X301960*
X306460*
X322260Y992204*
X298260Y547704*
X293760*
X325760Y507704*
X303260Y547704*
X325660Y548204*
X292260Y470204*
X296260*
X300260*
X304260*
X308260*
X312260*
X327760Y492704*
X284481Y1428833*
X275960Y1389704*
X267760Y1401904*
X284581Y1414733*
X269925Y1336075*
X272825Y1318575*
X277025*
X287725Y1309875*
X266760Y1269204*
X253560Y1272304*
X262760Y1269204*
X272260Y1022704*
X268260*
X264260*
X276260*
X280760Y1024104*
X285260*
X282160Y968804*
X286260Y968704*
X264629Y540823*
X260429Y541623*
X268929Y540823*
X255860Y541704*
X270260Y480704*
X274760*
X279260*
X284260Y470204*
X288260*
X283360Y480804*
X272760Y497804*
G54D243*
G55*
X388901Y288004D03*
X360619*
G54D244*
G55*
X365060Y1715704D03*
X381260Y1674204*
X347760Y1377504*
X344660Y981904*
X353660Y943504*
X337413Y1907106*
X304360Y1588404*
X329731Y1434825*
X314160Y982504*
Y977704*
X326460Y513004*
X314460Y494004*
X255360Y1436404*
X255560Y1415204*
X239239Y1354969*
X260960Y506004*
G54D245*
G55*
X371360Y1084704D03*
Y1073704*
X357460Y981904*
Y992904*
X382260Y946004*
Y935004*
X325260Y1037504*
Y1026504*
X274260Y1236504*
Y1247504*
G54D246*
G55*
X278960Y496704D03*
Y487704*
G54D247*
G55*
X349458Y1911957D03*
X349860Y1896750*
X346060Y1227004*
X345560Y1249404*
X367460Y955404*
X317760Y1371004*
X274895Y1357183*
G54D248*
G55*
X369460Y208204D03*
X330860Y1430704*
X321560*
X319060Y1415204*
X310060Y1374804*
X304760Y1365004*
X247060Y1432104*
X256760Y1432004*
G54D249*
G55*
X296260Y559050D03*
X300135Y566550*
X292385*
G54D250*
G55*
X351625Y1606604D03*
X310525Y1606704*
X321895Y1606604*
X280795Y1606704*
X263425Y460804*
X233695*
G54D251*
G55*
X357359Y1018904D03*
X334561*
G54D21*
G55*
X324803Y220669D03*
Y145473*
X242323Y639764*
X259843Y220669*
Y145473*
G54D252*
G55*
X309378Y506904D03*
X306819*
X304260*
X301701*
X299142*
Y526104*
X301701*
X304260*
X306819*
X309378*
G54D253*
G55*
X352260Y1528504D03*
X347260*
X342260*
X360860Y392904*
X355860*
X350860*
X345860*
X324760Y1529004*
X319760*
X314760*
X309760*
X337260Y1528504*
X292760Y393004*
X327760*
X322760*
X317760*
X312760*
X280260Y1529004*
X275260*
X270260*
X265260*
X252260*
X247260*
X242260*
X237260*
X258760Y393004*
X253760*
X248760*
X243760*
X287760*
X282760*
X277760*
G54D254*
G55*
X259843Y195079D03*
G54D255*
G55*
X294660Y511386D03*
Y513945*
Y516504*
Y519063*
Y521622*
X313860*
Y519063*
Y516504*
Y513945*
Y511386*
G54D256*
G55*
X331925Y1423754D03*
X333890*
X335860*
X337830*
X339795*
Y1407454*
X337830*
X335860*
X333890*
X331925*
X312550Y1355875*
X310585*
X308615*
X306645*
X304680*
X302710*
X300740*
X298770*
X296805*
X294835*
X292865*
X290900*
Y1322475*
X292865*
X294835*
X296805*
X298770*
X300740*
X302710*
X304680*
X306645*
X308615*
X310585*
X312550*
X268125Y1425554*
X270090*
X272060*
X274030*
X275995*
Y1409254*
X274030*
X272060*
X270090*
X268125*
G54D257*
G55*
X343860Y988454D03*
Y992204*
Y995954*
X333260*
Y992204*
Y988454*
G54D258*
G55*
X304260Y516504D03*
G54D259*
G55*
X318425Y1328350D03*
Y1330315*
Y1332285*
Y1334255*
Y1336220*
Y1338190*
Y1340160*
Y1342130*
Y1344095*
Y1346065*
Y1348035*
Y1350000*
X285025*
Y1348035*
Y1346065*
Y1344095*
Y1342130*
Y1340160*
Y1338190*
Y1336220*
Y1334255*
Y1332285*
Y1330315*
Y1328350*
G54D196*
G55*
X271260Y1904004D03*
X268760Y62504*
G54D23*
X-448201Y-82763D02*
G01Y-162763D01*
Y-118263D02*
G01X752899D01*
X-448201Y-162763D02*
G01X752899D01*
X-452201Y-66763D02*
G75*
G03X-452201Y-66763I-12000D01*
X-457351D02*
G03X-457351Y-66763I-6850D01*
X-464201Y-82763D02*
G01Y-50763D01*
X-448201Y-66763D02*
G01X-480201D01*
X-448201Y-82763D02*
G01X752899D01*
X-34601D02*
G01Y-162763D01*
X102899Y-82763D02*
G01Y-162763D01*
X217899Y-82763D02*
G01Y-162763D01*
X385399Y-82763D02*
G01Y-162763D01*
X555399Y-82763D02*
G01Y-162763D01*
X752899Y-82763D02*
G01Y-162763D01*
X780899Y-66763D02*
G03X780899Y-66763I-12000D01*
X775749D02*
G03X775749Y-66763I-6850D01*
X768899Y-82763D02*
G01Y-50763D01*
X784899Y-66763D02*
G01X752899D01*
G54D24*
X-430254Y-152763D02*
G01Y-135263D01*
X-421958D02*
G01X-430254Y-146055D01*
X-420648Y-152763D02*
G01X-426543Y-141097D01*
X-412973Y-152763D02*
G01Y-135263D01*
X-402929Y-152763*
Y-135263*
X-390451Y-152763D02*
G01X-392198Y-152471D01*
X-393726Y-151305*
X-395036Y-149555*
X-395910Y-147513*
X-396346Y-145180*
Y-142846*
X-395910Y-140513*
X-395036Y-138471*
X-393726Y-136722*
X-392198Y-135555*
X-390451Y-135263*
X-388705Y-135555*
X-387176Y-136722*
X-385866Y-138471*
X-384992Y-140513*
X-384556Y-142846*
Y-145180*
X-384992Y-147513*
X-385866Y-149555*
X-387176Y-151305*
X-388705Y-152471*
X-390451Y-152763*
X-377536D02*
G01X-368366Y-135263D01*
X-377536D02*
G01X-368366Y-152763D01*
X-362001Y-158596D02*
G01X-348901D01*
X-342099Y-152763D02*
G01Y-135263D01*
X-333803*
X-336859Y-143721D02*
G01X-342099D01*
X-325910Y-152763D02*
G01X-320451Y-135263D01*
X-314992Y-152763*
X-316958Y-146638D02*
G01X-323945D01*
X-307973Y-152763D02*
G01Y-135263D01*
X-297929Y-152763*
Y-135263*
X-263148Y-136722D02*
G01X-264458Y-135846D01*
X-265986Y-135263*
X-267733*
X-269698Y-136138*
X-271226Y-137596*
X-272318Y-139347*
X-273191Y-142263*
X-273410Y-144888*
X-272973Y-147513*
X-272318Y-149263*
X-271008Y-151013*
X-269479Y-152180*
X-267951Y-152763*
X-266423*
X-264894Y-152180*
X-263584Y-151305*
X-262492Y-150139*
X-250451Y-152763D02*
G01X-252198Y-152471D01*
X-253726Y-151305*
X-255036Y-149555*
X-255910Y-147513*
X-256346Y-145180*
Y-142846*
X-255910Y-140513*
X-255036Y-138471*
X-253726Y-136722*
X-252198Y-135555*
X-250451Y-135263*
X-248705Y-135555*
X-247176Y-136722*
X-245866Y-138471*
X-244992Y-140513*
X-244556Y-142846*
Y-145180*
X-244992Y-147513*
X-245866Y-149555*
X-247176Y-151305*
X-248705Y-152471*
X-250451Y-152763*
X-237973D02*
G01Y-135263D01*
X-227929Y-152763*
Y-135263*
X-215451D02*
G01Y-152763D01*
X-220473Y-135263D02*
G01X-210429D01*
X-202318Y-152763D02*
G01Y-135263D01*
X-196859*
X-195113Y-136138*
X-194021Y-137305*
X-193584Y-139638*
X-194021Y-141972*
X-195331Y-143430*
X-196859Y-144305*
X-202318*
X-196859D02*
G01X-193584Y-152763D01*
X-180451D02*
G01X-182198Y-152471D01*
X-183726Y-151305*
X-185036Y-149555*
X-185910Y-147513*
X-186346Y-145180*
Y-142846*
X-185910Y-140513*
X-185036Y-138471*
X-183726Y-136722*
X-182198Y-135555*
X-180451Y-135263*
X-178705Y-135555*
X-177176Y-136722*
X-175866Y-138471*
X-174992Y-140513*
X-174556Y-142846*
Y-145180*
X-174992Y-147513*
X-175866Y-149555*
X-177176Y-151305*
X-178705Y-152471*
X-180451Y-152763*
X-167318Y-135263D02*
G01Y-152763D01*
X-158584*
X-126205Y-143430D02*
G01X-125331Y-142555D01*
X-124676Y-141097*
X-124239Y-139054*
X-124676Y-137305*
X-125549Y-136138*
X-127078Y-135263*
X-132973*
Y-152763*
X-125768*
X-124239Y-151597*
X-123366Y-149846*
X-122929Y-147805*
X-123366Y-145763*
X-124676Y-144013*
X-126205Y-143430*
X-132973*
X-110451Y-152763D02*
G01X-112198Y-152471D01*
X-113726Y-151305*
X-115036Y-149555*
X-115910Y-147513*
X-116346Y-145180*
Y-142846*
X-115910Y-140513*
X-115036Y-138471*
X-113726Y-136722*
X-112198Y-135555*
X-110451Y-135263*
X-108705Y-135555*
X-107176Y-136722*
X-105866Y-138471*
X-104992Y-140513*
X-104556Y-142846*
Y-145180*
X-104992Y-147513*
X-105866Y-149555*
X-107176Y-151305*
X-108705Y-152471*
X-110451Y-152763*
X-98410D02*
G01X-92951Y-135263D01*
X-87492Y-152763*
X-89458Y-146638D02*
G01X-96445D01*
X-79818Y-152763D02*
G01Y-135263D01*
X-74359*
X-72613Y-136138*
X-71521Y-137305*
X-71084Y-139638*
X-71521Y-141972*
X-72831Y-143430*
X-74359Y-144305*
X-79818*
X-74359D02*
G01X-71084Y-152763D01*
X-62754D02*
G01Y-135263D01*
X-58388*
X-56641Y-136138*
X-55331Y-137305*
X-54239Y-139054*
X-53366Y-141097*
X-53148Y-144013*
X-53366Y-146930*
X-54239Y-148972*
X-55331Y-150722*
X-56641Y-151888*
X-58388Y-152763*
X-62754*
X-282378Y-107763D02*
G01Y-90263D01*
X-276701Y-104846*
X-271024Y-90263*
Y-107763*
X-259201D02*
G01X-260511Y-107471D01*
X-261821Y-106305*
X-262695Y-104263*
X-263131Y-101930*
X-262695Y-99596*
X-261821Y-97555*
X-260511Y-96388*
X-259201Y-96097*
X-257891Y-96388*
X-256581Y-97555*
X-255708Y-99596*
X-255489Y-101930*
X-255708Y-104263*
X-256581Y-106305*
X-257891Y-107471*
X-259201Y-107763*
X-237771Y-90263D02*
G01Y-107763D01*
Y-105139D02*
G01X-238644Y-106597D01*
X-239955Y-107471*
X-241483Y-107763*
X-243229Y-107180*
X-244539Y-105722*
X-245413Y-103972*
X-245631Y-101930*
X-245413Y-99888*
X-244539Y-98138*
X-243229Y-96680*
X-241483Y-96097*
X-239955Y-96388*
X-238863Y-96972*
X-237771Y-98138*
X-227476Y-99888D02*
G01X-220489D01*
X-221144Y-97846*
X-222236Y-96680*
X-223764Y-96097*
X-225293Y-96388*
X-226603Y-97263*
X-227476Y-99305*
X-227913Y-101055*
Y-102805*
X-227476Y-104555*
X-226384Y-106305*
X-225074Y-107471*
X-223546Y-107763*
X-222018Y-107180*
X-220489Y-105430*
X-206701Y-107763D02*
G01Y-90263D01*
X-901Y-152763D02*
G01Y-135263D01*
X-3521Y-138763*
Y-152763D02*
G01X1719D01*
X12451Y-138180D02*
G01X13761Y-136430D01*
X15289Y-135555*
X17036Y-135263*
X19219Y-135846*
X20747Y-137305*
X21184Y-139054*
X20966Y-140805*
X20092Y-142263*
X15726Y-145180*
X13761Y-147221*
X12451Y-150139*
X12014Y-152763*
X21184*
X36719D02*
G01Y-135263D01*
X28640Y-147805*
X39558*
X46796Y-149263D02*
G01X48105Y-151305D01*
X49852Y-152471*
X51817Y-152763*
X53564Y-152471*
X55311Y-151013*
X56402Y-149263*
X56621Y-147513*
X56184Y-145472*
X54656Y-144013*
X53127Y-143430*
X51162*
X53127D02*
G01X54437Y-142555D01*
X55529Y-141097*
X55966Y-139347*
X55529Y-137596*
X54437Y-136138*
X52472Y-135263*
X50507Y-135555*
X48542Y-136722*
X64296Y-149263D02*
G01X65605Y-151305D01*
X67352Y-152471*
X69317Y-152763*
X71064Y-152471*
X72811Y-151013*
X73902Y-149263*
X74121Y-147513*
X73684Y-145472*
X72156Y-144013*
X70627Y-143430*
X68662*
X70627D02*
G01X71937Y-142555D01*
X73029Y-141097*
X73466Y-139347*
X73029Y-137596*
X71937Y-136138*
X69972Y-135263*
X68007Y-135555*
X66042Y-136722*
X-14018Y-107763D02*
G01Y-90263D01*
X-8778*
X-7031Y-91138*
X-5721Y-93180*
X-5284Y-95513*
X-5721Y-97846*
X-6813Y-99596*
X-8778Y-100472*
X-14018*
X12652Y-91722D02*
G01X11342Y-90846D01*
X9814Y-90263*
X8067*
X6102Y-91138*
X4574Y-92596*
X3482Y-94347*
X2609Y-97263*
X2390Y-99888*
X2827Y-102513*
X3482Y-104263*
X4792Y-106013*
X6321Y-107180*
X7849Y-107763*
X9377*
X10906Y-107180*
X12216Y-106305*
X13308Y-105139*
X27095Y-98430D02*
G01X27969Y-97555D01*
X28624Y-96097*
X29061Y-94054*
X28624Y-92305*
X27751Y-91138*
X26222Y-90263*
X20327*
Y-107763*
X27532*
X29061Y-106597*
X29934Y-104846*
X30371Y-102805*
X29934Y-100763*
X28624Y-99013*
X27095Y-98430*
X20327*
X36299Y-113596D02*
G01X49399D01*
X55327Y-107763D02*
G01Y-90263D01*
X65371Y-107763*
Y-90263*
X77849Y-107763D02*
G01X76102Y-107471D01*
X74574Y-106305*
X73264Y-104555*
X72390Y-102513*
X71954Y-100180*
Y-97846*
X72390Y-95513*
X73264Y-93471*
X74574Y-91722*
X76102Y-90555*
X77849Y-90263*
X79595Y-90555*
X81124Y-91722*
X82434Y-93471*
X83308Y-95513*
X83744Y-97846*
Y-100180*
X83308Y-102513*
X82434Y-104555*
X81124Y-106305*
X79595Y-107471*
X77849Y-107763*
X128690Y-90263D02*
G01X134149Y-107763D01*
X139608Y-90263*
X156016Y-107763D02*
G01X147282D01*
Y-90263*
X156016*
X152522Y-98721D02*
G01X147282D01*
X164782Y-107763D02*
G01Y-90263D01*
X170241*
X171987Y-91138*
X173079Y-92305*
X173516Y-94638*
X173079Y-96972*
X171769Y-98430*
X170241Y-99305*
X164782*
X170241D02*
G01X173516Y-107763D01*
X186649Y-108346D02*
G01X186212Y-108055D01*
Y-107471*
X186649Y-107180*
X187086Y-107471*
Y-108055*
X186649Y-108346*
X151649Y-152763D02*
G01Y-135263D01*
X149029Y-138763*
Y-152763D02*
G01X154269D01*
X163472D02*
G01Y-135263D01*
X169149Y-149846*
X174826Y-135263*
Y-152763*
X266599Y-135263D02*
G01Y-152763D01*
X261577Y-135263D02*
G01X271621D01*
X278422Y-152763D02*
G01Y-135263D01*
X284099Y-149846*
X289776Y-135263*
Y-152763*
X296140D02*
G01X301599Y-135263D01*
X307058Y-152763*
X305092Y-146638D02*
G01X298105D01*
X314514Y-150430D02*
G01X316261Y-151888D01*
X318226Y-152763*
X319972*
X321719Y-151888*
X323029Y-150430*
X323684Y-148388*
X323247Y-146347*
X322156Y-144596*
X320191Y-143430*
X317571Y-142846*
X316042Y-141680*
X315387Y-139638*
X315824Y-137596*
X316916Y-136138*
X318444Y-135263*
X319972*
X321501Y-135846*
X322811Y-137305*
X331796Y-152763D02*
G01Y-135263D01*
X340092D02*
G01X331796Y-146055D01*
X341402Y-152763D02*
G01X335507Y-141097D01*
X253482Y-90263D02*
G01Y-107763D01*
X262216*
X279279D02*
G01Y-96097D01*
Y-98138D02*
G01X278406Y-96972D01*
X277095Y-96388*
X275567Y-96097*
X274039Y-96680*
X272729Y-97846*
X271855Y-99596*
X271419Y-101930*
X271855Y-104263*
X272729Y-106013*
X274039Y-107180*
X275567Y-107763*
X277095Y-107471*
X278406Y-106597*
X279279Y-105430*
X288264Y-113013D02*
G01X289574Y-113596D01*
X291321Y-113013*
X292412Y-111847*
X293286Y-110388*
X294595Y-105722*
X297434Y-96097*
X290447D02*
G01X294595Y-105722D01*
X307074Y-99888D02*
G01X314061D01*
X313406Y-97846*
X312314Y-96680*
X310786Y-96097*
X309257Y-96388*
X307947Y-97263*
X307074Y-99305*
X306637Y-101055*
Y-102805*
X307074Y-104555*
X308166Y-106305*
X309476Y-107471*
X311004Y-107763*
X312532Y-107180*
X314061Y-105430*
X324792Y-107763D02*
G01Y-96097D01*
Y-98430D02*
G01X325884Y-97263D01*
X326976Y-96388*
X328504Y-96097*
X329595Y-96388*
X330906Y-97263*
X342074Y-105722D02*
G01X343166Y-106888D01*
X344694Y-107763*
X346004*
X347314Y-107180*
X348187Y-106305*
X348624Y-105139*
X348406Y-103388*
X347532Y-102513*
X343602Y-100763*
X342729Y-98721*
X343166Y-97263*
X344039Y-96388*
X345349Y-96097*
X346659Y-96388*
X347969Y-97263*
X404346Y-107763D02*
G01Y-90263D01*
X408712*
X410459Y-91138*
X411769Y-92305*
X412861Y-94054*
X413734Y-96097*
X413952Y-99013*
X413734Y-101930*
X412861Y-103972*
X411769Y-105722*
X410459Y-106888*
X408712Y-107763*
X404346*
X423374Y-99888D02*
G01X430361D01*
X429706Y-97846*
X428614Y-96680*
X427086Y-96097*
X425557Y-96388*
X424247Y-97263*
X423374Y-99305*
X422937Y-101055*
Y-102805*
X423374Y-104555*
X424466Y-106305*
X425776Y-107471*
X427304Y-107763*
X428832Y-107180*
X430361Y-105430*
X440874Y-105722D02*
G01X441966Y-106888D01*
X443494Y-107763*
X444804*
X446114Y-107180*
X446987Y-106305*
X447424Y-105139*
X447206Y-103388*
X446332Y-102513*
X442402Y-100763*
X441529Y-98721*
X441966Y-97263*
X442839Y-96388*
X444149Y-96097*
X445459Y-96388*
X446769Y-97263*
X461649Y-96097D02*
G01Y-107763D01*
Y-91430D02*
G01X461212Y-91138D01*
Y-90555*
X461649Y-90263*
X462086Y-90555*
Y-91138*
X461649Y-91430*
X476092Y-112138D02*
G01X477621Y-113305D01*
X479367Y-113596*
X480895Y-113305*
X482206Y-111847*
X483079Y-109805*
Y-96097*
Y-98430D02*
G01X482206Y-97263D01*
X480895Y-96388*
X479367Y-96097*
X477621Y-96680*
X476529Y-97846*
X475655Y-99888*
X475219Y-101930*
X475437Y-103680*
X476311Y-105722*
X477621Y-107180*
X479367Y-107763*
X480677Y-107471*
X482206Y-106305*
X483079Y-105139*
X492937Y-107763D02*
G01Y-96097D01*
Y-99013D02*
G01X493811Y-97555D01*
X495121Y-96388*
X496867Y-96097*
X498395Y-96388*
X499706Y-97555*
X500361Y-99596*
Y-107763*
X510874Y-99888D02*
G01X517861D01*
X517206Y-97846*
X516114Y-96680*
X514586Y-96097*
X513057Y-96388*
X511747Y-97263*
X510874Y-99305*
X510437Y-101055*
Y-102805*
X510874Y-104555*
X511966Y-106305*
X513276Y-107471*
X514804Y-107763*
X516332Y-107180*
X517861Y-105430*
X528592Y-107763D02*
G01Y-96097D01*
Y-98430D02*
G01X529684Y-97263D01*
X530776Y-96388*
X532304Y-96097*
X533395Y-96388*
X534706Y-97263*
X448096Y-152763D02*
G01Y-135263D01*
X452462*
X454209Y-136138*
X455519Y-137305*
X456611Y-139054*
X457484Y-141097*
X457702Y-144013*
X457484Y-146930*
X456611Y-148972*
X455519Y-150722*
X454209Y-151888*
X452462Y-152763*
X448096*
X470399Y-141097D02*
G01Y-152763D01*
Y-136430D02*
G01X469962Y-136138D01*
Y-135555*
X470399Y-135263*
X470836Y-135555*
Y-136138*
X470399Y-136430*
X487899Y-152763D02*
G01X486589Y-152471D01*
X485279Y-151305*
X484405Y-149263*
X483969Y-146930*
X484405Y-144596*
X485279Y-142555*
X486589Y-141388*
X487899Y-141097*
X489209Y-141388*
X490519Y-142555*
X491392Y-144596*
X491611Y-146930*
X491392Y-149263*
X490519Y-151305*
X489209Y-152471*
X487899Y-152763*
X575349D02*
G01Y-135263D01*
X572729Y-138763*
Y-152763D02*
G01X577969D01*
X588701Y-138180D02*
G01X590011Y-136430D01*
X591539Y-135555*
X593286Y-135263*
X595469Y-135846*
X596997Y-137305*
X597434Y-139054*
X597216Y-140805*
X596342Y-142263*
X591976Y-145180*
X590011Y-147221*
X588701Y-150139*
X588264Y-152763*
X597434*
X606419Y-153346D02*
G01X614279Y-135263D01*
X627849D02*
G01X626102Y-135846D01*
X624792Y-137305*
X623919Y-139054*
X623264Y-141388*
X623046Y-144013*
X623264Y-146638*
X623919Y-148972*
X624792Y-150722*
X626102Y-152180*
X627849Y-152763*
X629595Y-152180*
X630906Y-150722*
X631779Y-148972*
X632434Y-146638*
X632652Y-144013*
X632434Y-141388*
X631779Y-139054*
X630906Y-137305*
X629595Y-135846*
X627849Y-135263*
X644912Y-152763D02*
G01X645349Y-148972D01*
X646004Y-145763*
X646877Y-142846*
X647969Y-139638*
X649716Y-135263*
X640982*
X658919Y-153346D02*
G01X666779Y-135263D01*
X676201Y-138180D02*
G01X677511Y-136430D01*
X679039Y-135555*
X680786Y-135263*
X682969Y-135846*
X684497Y-137305*
X684934Y-139054*
X684716Y-140805*
X683842Y-142263*
X679476Y-145180*
X677511Y-147221*
X676201Y-150139*
X675764Y-152763*
X684934*
X697849Y-135263D02*
G01X696102Y-135846D01*
X694792Y-137305*
X693919Y-139054*
X693264Y-141388*
X693046Y-144013*
X693264Y-146638*
X693919Y-148972*
X694792Y-150722*
X696102Y-152180*
X697849Y-152763*
X699595Y-152180*
X700906Y-150722*
X701779Y-148972*
X702434Y-146638*
X702652Y-144013*
X702434Y-141388*
X701779Y-139054*
X700906Y-137305*
X699595Y-135846*
X697849Y-135263*
X715349Y-152763D02*
G01Y-135263D01*
X712729Y-138763*
Y-152763D02*
G01X717969D01*
X728701Y-138180D02*
G01X730011Y-136430D01*
X731539Y-135555*
X733286Y-135263*
X735469Y-135846*
X736997Y-137305*
X737434Y-139054*
X737216Y-140805*
X736342Y-142263*
X731976Y-145180*
X730011Y-147221*
X728701Y-150139*
X728264Y-152763*
X737434*
X623046Y-107763D02*
G01Y-90263D01*
X627412*
X629159Y-91138*
X630469Y-92305*
X631561Y-94054*
X632434Y-96097*
X632652Y-99013*
X632434Y-101930*
X631561Y-103972*
X630469Y-105722*
X629159Y-106888*
X627412Y-107763*
X623046*
X649279D02*
G01Y-96097D01*
Y-98138D02*
G01X648406Y-96972D01*
X647095Y-96388*
X645567Y-96097*
X644039Y-96680*
X642729Y-97846*
X641855Y-99596*
X641419Y-101930*
X641855Y-104263*
X642729Y-106013*
X644039Y-107180*
X645567Y-107763*
X647095Y-107471*
X648406Y-106597*
X649279Y-105430*
X662849Y-90263D02*
G01Y-107763D01*
X659792Y-96097D02*
G01X665906D01*
X677074Y-99888D02*
G01X684061D01*
X683406Y-97846*
X682314Y-96680*
X680786Y-96097*
X679257Y-96388*
X677947Y-97263*
X677074Y-99305*
X676637Y-101055*
Y-102805*
X677074Y-104555*
X678166Y-106305*
X679476Y-107471*
X681004Y-107763*
X682532Y-107180*
X684061Y-105430*
M02*
